FILE_TYPE = MACRO_DRAWING;
SET COLOR_WIRE YELLOW;
SET COLOR_PROP ORANGE;
SET COLOR_DOT WHITE;
SET COLOR_ARC YELLOW;
SET COLOR_BODY GREEN;
SET COLOR_NOTE PURPLE;
SET PROP_DISPLAY VALUE;
SET PAGE_NUMBER P10;
FORCEADD GENOA_SP5..1
(-4350 3700);
FORCEPROP 1 LAST LOCATION U25
J 0
(-4995 6506);
DISPLAY 0.489362 (-4995 6506);
PAINT SKYBLUE (-4995 6506);
FORCEPROP 0 LAST $SEC 1
J 0
(-4975 6550);
DISPLAY 0.680851 (-4975 6550);
PAINT MONO (-4975 6550);
DISPLAY INVISIBLE (-4975 6550);
FORCEPROP 0 LAST CDS_SEC 1
J 0
(-5000 6450);
DISPLAY 1.021277 (-5000 6450);
DISPLAY INVISIBLE (-5000 6450);
FORCEPROP 0 LASTPIN (-5150 3100) $PN BC74
J 2
(-5160 3110);
DISPLAY 0.489362 (-5160 3110);
PAINT MONO (-5160 3110);
FORCEPROP 0 LASTPIN (-5150 3050) $PN BD74
J 2
(-5160 3060);
DISPLAY 0.489362 (-5160 3060);
PAINT MONO (-5160 3060);
FORCEPROP 0 LASTPIN (-5150 1950) $PN BF74
J 2
(-5160 1960);
DISPLAY 0.489362 (-5160 1960);
PAINT MONO (-5160 1960);
FORCEPROP 0 LASTPIN (-5150 1900) $PN BG74
J 2
(-5160 1910);
DISPLAY 0.489362 (-5160 1910);
PAINT MONO (-5160 1910);
FORCEPROP 0 LASTPIN (-5150 2250) $PN AR74
J 2
(-5160 2260);
DISPLAY 0.489362 (-5160 2260);
PAINT MONO (-5160 2260);
FORCEPROP 0 LASTPIN (-5150 2150) $PN AT74
J 2
(-5160 2160);
DISPLAY 0.489362 (-5160 2160);
PAINT MONO (-5160 2160);
FORCEPROP 0 LASTPIN (-5150 2950) $PN AV74
J 2
(-5160 2960);
DISPLAY 0.489362 (-5160 2960);
PAINT MONO (-5160 2960);
FORCEPROP 0 LASTPIN (-5150 2900) $PN AW73
J 2
(-5160 2910);
DISPLAY 0.489362 (-5160 2910);
PAINT MONO (-5160 2910);
FORCEPROP 0 LASTPIN (-5150 2800) $PN BN73
J 2
(-5160 2810);
DISPLAY 0.489362 (-5160 2810);
PAINT MONO (-5160 2810);
FORCEPROP 0 LASTPIN (-5150 1800) $PN AU74
J 2
(-5160 1810);
DISPLAY 0.489362 (-5160 1810);
PAINT MONO (-5160 1810);
FORCEPROP 0 LASTPIN (-5150 1750) $PN AV72
J 2
(-5160 1760);
DISPLAY 0.489362 (-5160 1760);
PAINT MONO (-5160 1760);
FORCEPROP 0 LASTPIN (-5150 1650) $PN BP72
J 2
(-5160 1660);
DISPLAY 0.489362 (-5160 1660);
PAINT MONO (-5160 1660);
FORCEPROP 0 LASTPIN (-5150 3950) $PN AW74
J 2
(-5160 3960);
DISPLAY 0.489362 (-5160 3960);
PAINT MONO (-5160 3960);
FORCEPROP 0 LASTPIN (-5150 3900) $PN AY74
J 2
(-5160 3910);
DISPLAY 0.489362 (-5160 3910);
PAINT MONO (-5160 3910);
FORCEPROP 0 LASTPIN (-5150 3850) $PN AY72
J 2
(-5160 3860);
DISPLAY 0.489362 (-5160 3860);
PAINT MONO (-5160 3860);
FORCEPROP 0 LASTPIN (-5150 3800) $PN BA73
J 2
(-5160 3810);
DISPLAY 0.489362 (-5160 3810);
PAINT MONO (-5160 3810);
FORCEPROP 0 LASTPIN (-5150 3750) $PN BA74
J 2
(-5160 3760);
DISPLAY 0.489362 (-5160 3760);
PAINT MONO (-5160 3760);
FORCEPROP 0 LASTPIN (-5150 3700) $PN BB74
J 2
(-5160 3710);
DISPLAY 0.489362 (-5160 3710);
PAINT MONO (-5160 3710);
FORCEPROP 0 LASTPIN (-5150 3650) $PN BB72
J 2
(-5160 3660);
DISPLAY 0.489362 (-5160 3660);
PAINT MONO (-5160 3660);
FORCEPROP 0 LASTPIN (-3550 2500) $PN AJ74
J 0
(-3540 2510);
DISPLAY 0.489362 (-3540 2510);
PAINT MONO (-3540 2510);
FORCEPROP 0 LASTPIN (-3550 2450) $PN AK72
J 0
(-3540 2460);
DISPLAY 0.489362 (-3540 2460);
PAINT MONO (-3540 2460);
FORCEPROP 0 LASTPIN (-3550 2400) $PN AK74
J 0
(-3540 2410);
DISPLAY 0.489362 (-3540 2410);
PAINT MONO (-3540 2410);
FORCEPROP 0 LASTPIN (-3550 2350) $PN AL73
J 0
(-3540 2360);
DISPLAY 0.489362 (-3540 2360);
PAINT MONO (-3540 2360);
FORCEPROP 0 LASTPIN (-3550 2300) $PN AN74
J 0
(-3540 2310);
DISPLAY 0.489362 (-3540 2310);
PAINT MONO (-3540 2310);
FORCEPROP 0 LASTPIN (-3550 2250) $PN AP72
J 0
(-3540 2260);
DISPLAY 0.489362 (-3540 2260);
PAINT MONO (-3540 2260);
FORCEPROP 0 LASTPIN (-3550 2200) $PN AP74
J 0
(-3540 2210);
DISPLAY 0.489362 (-3540 2210);
PAINT MONO (-3540 2210);
FORCEPROP 0 LASTPIN (-3550 2150) $PN AR73
J 0
(-3540 2160);
DISPLAY 0.489362 (-3540 2160);
PAINT MONO (-3540 2160);
FORCEPROP 0 LASTPIN (-3550 6100) $PN E74
J 0
(-3540 6110);
DISPLAY 0.489362 (-3540 6110);
PAINT MONO (-3540 6110);
FORCEPROP 0 LASTPIN (-3550 6050) $PN F72
J 0
(-3540 6060);
DISPLAY 0.489362 (-3540 6060);
PAINT MONO (-3540 6060);
FORCEPROP 0 LASTPIN (-3550 6000) $PN F74
J 0
(-3540 6010);
DISPLAY 0.489362 (-3540 6010);
PAINT MONO (-3540 6010);
FORCEPROP 0 LASTPIN (-3550 5950) $PN G73
J 0
(-3540 5960);
DISPLAY 0.489362 (-3540 5960);
PAINT MONO (-3540 5960);
FORCEPROP 0 LASTPIN (-3550 5900) $PN J74
J 0
(-3540 5910);
DISPLAY 0.489362 (-3540 5910);
PAINT MONO (-3540 5910);
FORCEPROP 0 LASTPIN (-3550 5850) $PN K72
J 0
(-3540 5860);
DISPLAY 0.489362 (-3540 5860);
PAINT MONO (-3540 5860);
FORCEPROP 0 LASTPIN (-3550 5800) $PN K74
J 0
(-3540 5810);
DISPLAY 0.489362 (-3540 5810);
PAINT MONO (-3540 5810);
FORCEPROP 0 LASTPIN (-3550 5750) $PN L73
J 0
(-3540 5760);
DISPLAY 0.489362 (-3540 5760);
PAINT MONO (-3540 5760);
FORCEPROP 0 LASTPIN (-3550 5650) $PN L74
J 0
(-3540 5660);
DISPLAY 0.489362 (-3540 5660);
PAINT MONO (-3540 5660);
FORCEPROP 0 LASTPIN (-3550 5600) $PN M72
J 0
(-3540 5610);
DISPLAY 0.489362 (-3540 5610);
PAINT MONO (-3540 5610);
FORCEPROP 0 LASTPIN (-3550 5550) $PN M74
J 0
(-3540 5560);
DISPLAY 0.489362 (-3540 5560);
PAINT MONO (-3540 5560);
FORCEPROP 0 LASTPIN (-3550 5500) $PN N73
J 0
(-3540 5510);
DISPLAY 0.489362 (-3540 5510);
PAINT MONO (-3540 5510);
FORCEPROP 0 LASTPIN (-3550 5450) $PN R74
J 0
(-3540 5460);
DISPLAY 0.489362 (-3540 5460);
PAINT MONO (-3540 5460);
FORCEPROP 0 LASTPIN (-3550 5400) $PN T72
J 0
(-3540 5410);
DISPLAY 0.489362 (-3540 5410);
PAINT MONO (-3540 5410);
FORCEPROP 0 LASTPIN (-3550 5350) $PN T74
J 0
(-3540 5360);
DISPLAY 0.489362 (-3540 5360);
PAINT MONO (-3540 5360);
FORCEPROP 0 LASTPIN (-3550 5300) $PN U73
J 0
(-3540 5310);
DISPLAY 0.489362 (-3540 5310);
PAINT MONO (-3540 5310);
FORCEPROP 0 LASTPIN (-3550 5200) $PN U74
J 0
(-3540 5210);
DISPLAY 0.489362 (-3540 5210);
PAINT MONO (-3540 5210);
FORCEPROP 0 LASTPIN (-3550 5150) $PN V72
J 0
(-3540 5160);
DISPLAY 0.489362 (-3540 5160);
PAINT MONO (-3540 5160);
FORCEPROP 0 LASTPIN (-3550 5100) $PN V74
J 0
(-3540 5110);
DISPLAY 0.489362 (-3540 5110);
PAINT MONO (-3540 5110);
FORCEPROP 0 LASTPIN (-3550 5050) $PN W73
J 0
(-3540 5060);
DISPLAY 0.489362 (-3540 5060);
PAINT MONO (-3540 5060);
FORCEPROP 0 LASTPIN (-3550 5000) $PN AA74
J 0
(-3540 5010);
DISPLAY 0.489362 (-3540 5010);
PAINT MONO (-3540 5010);
FORCEPROP 0 LASTPIN (-3550 4950) $PN AB72
J 0
(-3540 4960);
DISPLAY 0.489362 (-3540 4960);
PAINT MONO (-3540 4960);
FORCEPROP 0 LASTPIN (-3550 4900) $PN AB74
J 0
(-3540 4910);
DISPLAY 0.489362 (-3540 4910);
PAINT MONO (-3540 4910);
FORCEPROP 0 LASTPIN (-3550 4850) $PN AC73
J 0
(-3540 4860);
DISPLAY 0.489362 (-3540 4860);
PAINT MONO (-3540 4860);
FORCEPROP 0 LASTPIN (-3550 4750) $PN AC74
J 0
(-3540 4760);
DISPLAY 0.489362 (-3540 4760);
PAINT MONO (-3540 4760);
FORCEPROP 0 LASTPIN (-3550 4700) $PN AD72
J 0
(-3540 4710);
DISPLAY 0.489362 (-3540 4710);
PAINT MONO (-3540 4710);
FORCEPROP 0 LASTPIN (-3550 4650) $PN AD74
J 0
(-3540 4660);
DISPLAY 0.489362 (-3540 4660);
PAINT MONO (-3540 4660);
FORCEPROP 0 LASTPIN (-3550 4600) $PN AE73
J 0
(-3540 4610);
DISPLAY 0.489362 (-3540 4610);
PAINT MONO (-3540 4610);
FORCEPROP 0 LASTPIN (-3550 4550) $PN AG74
J 0
(-3540 4560);
DISPLAY 0.489362 (-3540 4560);
PAINT MONO (-3540 4560);
FORCEPROP 0 LASTPIN (-3550 4500) $PN AH72
J 0
(-3540 4510);
DISPLAY 0.489362 (-3540 4510);
PAINT MONO (-3540 4510);
FORCEPROP 0 LASTPIN (-3550 4450) $PN AH74
J 0
(-3540 4460);
DISPLAY 0.489362 (-3540 4460);
PAINT MONO (-3540 4460);
FORCEPROP 0 LASTPIN (-3550 4400) $PN AJ73
J 0
(-3540 4410);
DISPLAY 0.489362 (-3540 4410);
PAINT MONO (-3540 4410);
FORCEPROP 0 LASTPIN (-5150 6100) $PN G74
J 2
(-5160 6110);
DISPLAY 0.489362 (-5160 6110);
PAINT MONO (-5160 6110);
FORCEPROP 0 LASTPIN (-5150 6000) $PN N74
J 2
(-5160 6010);
DISPLAY 0.489362 (-5160 6010);
PAINT MONO (-5160 6010);
FORCEPROP 0 LASTPIN (-5150 5900) $PN W74
J 2
(-5160 5910);
DISPLAY 0.489362 (-5160 5910);
PAINT MONO (-5160 5910);
FORCEPROP 0 LASTPIN (-5150 5800) $PN AE74
J 2
(-5160 5810);
DISPLAY 0.489362 (-5160 5810);
PAINT MONO (-5160 5810);
FORCEPROP 0 LASTPIN (-5150 5700) $PN AL74
J 2
(-5160 5710);
DISPLAY 0.489362 (-5160 5710);
PAINT MONO (-5160 5710);
FORCEPROP 0 LASTPIN (-5150 5600) $PN J73
J 2
(-5160 5610);
DISPLAY 0.489362 (-5160 5610);
PAINT MONO (-5160 5610);
FORCEPROP 0 LASTPIN (-5150 5500) $PN R73
J 2
(-5160 5510);
DISPLAY 0.489362 (-5160 5510);
PAINT MONO (-5160 5510);
FORCEPROP 0 LASTPIN (-5150 5400) $PN AA73
J 2
(-5160 5410);
DISPLAY 0.489362 (-5160 5410);
PAINT MONO (-5160 5410);
FORCEPROP 0 LASTPIN (-5150 5300) $PN AG73
J 2
(-5160 5310);
DISPLAY 0.489362 (-5160 5310);
PAINT MONO (-5160 5310);
FORCEPROP 0 LASTPIN (-5150 5200) $PN AN73
J 2
(-5160 5210);
DISPLAY 0.489362 (-5160 5210);
PAINT MONO (-5160 5210);
FORCEPROP 0 LASTPIN (-5150 6050) $PN H74
J 2
(-5160 6060);
DISPLAY 0.489362 (-5160 6060);
PAINT MONO (-5160 6060);
FORCEPROP 0 LASTPIN (-5150 5950) $PN P74
J 2
(-5160 5960);
DISPLAY 0.489362 (-5160 5960);
PAINT MONO (-5160 5960);
FORCEPROP 0 LASTPIN (-5150 5850) $PN Y74
J 2
(-5160 5860);
DISPLAY 0.489362 (-5160 5860);
PAINT MONO (-5160 5860);
FORCEPROP 0 LASTPIN (-5150 5750) $PN AF74
J 2
(-5160 5760);
DISPLAY 0.489362 (-5160 5760);
PAINT MONO (-5160 5760);
FORCEPROP 0 LASTPIN (-5150 5650) $PN AM74
J 2
(-5160 5660);
DISPLAY 0.489362 (-5160 5660);
PAINT MONO (-5160 5660);
FORCEPROP 0 LASTPIN (-5150 5550) $PN H72
J 2
(-5160 5560);
DISPLAY 0.489362 (-5160 5560);
PAINT MONO (-5160 5560);
FORCEPROP 0 LASTPIN (-5150 5450) $PN P72
J 2
(-5160 5460);
DISPLAY 0.489362 (-5160 5460);
PAINT MONO (-5160 5460);
FORCEPROP 0 LASTPIN (-5150 5350) $PN Y72
J 2
(-5160 5360);
DISPLAY 0.489362 (-5160 5360);
PAINT MONO (-5160 5360);
FORCEPROP 0 LASTPIN (-5150 5250) $PN AF72
J 2
(-5160 5260);
DISPLAY 0.489362 (-5160 5260);
PAINT MONO (-5160 5260);
FORCEPROP 0 LASTPIN (-5150 5150) $PN AM72
J 2
(-5160 5160);
DISPLAY 0.489362 (-5160 5160);
PAINT MONO (-5160 5160);
FORCEPROP 0 LASTPIN (-5150 2700) $PN BC73
J 2
(-5160 2710);
DISPLAY 0.489362 (-5160 2710);
PAINT MONO (-5160 2710);
FORCEPROP 0 LASTPIN (-5150 2600) $PN BM72
J 2
(-5160 2610);
DISPLAY 0.489362 (-5160 2610);
PAINT MONO (-5160 2610);
FORCEPROP 0 LASTPIN (-5150 2550) $PN BN74
J 2
(-5160 2560);
DISPLAY 0.489362 (-5160 2560);
PAINT MONO (-5160 2560);
FORCEPROP 0 LASTPIN (-5150 2450) $PN BP74
J 2
(-5160 2460);
DISPLAY 0.489362 (-5160 2460);
PAINT MONO (-5160 2460);
FORCEPROP 0 LASTPIN (-5150 1550) $PN BL73
J 2
(-5160 1560);
DISPLAY 0.489362 (-5160 1560);
PAINT MONO (-5160 1560);
FORCEPROP 0 LASTPIN (-5150 1500) $PN BM74
J 2
(-5160 1510);
DISPLAY 0.489362 (-5160 1510);
PAINT MONO (-5160 1510);
FORCEPROP 0 LASTPIN (-5150 1400) $PN BR74
J 2
(-5160 1410);
DISPLAY 0.489362 (-5160 1410);
PAINT MONO (-5160 1410);
FORCEPROP 0 LASTPIN (-5150 3550) $PN BG73
J 2
(-5160 3560);
DISPLAY 0.489362 (-5160 3560);
PAINT MONO (-5160 3560);
FORCEPROP 0 LASTPIN (-5150 3500) $PN BH72
J 2
(-5160 3510);
DISPLAY 0.489362 (-5160 3510);
PAINT MONO (-5160 3510);
FORCEPROP 0 LASTPIN (-5150 3450) $PN BH74
J 2
(-5160 3460);
DISPLAY 0.489362 (-5160 3460);
PAINT MONO (-5160 3460);
FORCEPROP 0 LASTPIN (-5150 3400) $PN BJ74
J 2
(-5160 3410);
DISPLAY 0.489362 (-5160 3410);
PAINT MONO (-5160 3410);
FORCEPROP 0 LASTPIN (-5150 3350) $PN BJ73
J 2
(-5160 3360);
DISPLAY 0.489362 (-5160 3360);
PAINT MONO (-5160 3360);
FORCEPROP 0 LASTPIN (-5150 3300) $PN BK72
J 2
(-5160 3310);
DISPLAY 0.489362 (-5160 3310);
PAINT MONO (-5160 3310);
FORCEPROP 0 LASTPIN (-5150 3250) $PN BK74
J 2
(-5160 3260);
DISPLAY 0.489362 (-5160 3260);
PAINT MONO (-5160 3260);
FORCEPROP 0 LASTPIN (-3550 2050) $PN BY74
J 0
(-3540 2060);
DISPLAY 0.489362 (-3540 2060);
PAINT MONO (-3540 2060);
FORCEPROP 0 LASTPIN (-3550 2000) $PN CA73
J 0
(-3540 2010);
DISPLAY 0.489362 (-3540 2010);
PAINT MONO (-3540 2010);
FORCEPROP 0 LASTPIN (-3550 1950) $PN CA74
J 0
(-3540 1960);
DISPLAY 0.489362 (-3540 1960);
PAINT MONO (-3540 1960);
FORCEPROP 0 LASTPIN (-3550 1900) $PN CB72
J 0
(-3540 1910);
DISPLAY 0.489362 (-3540 1910);
PAINT MONO (-3540 1910);
FORCEPROP 0 LASTPIN (-3550 1850) $PN BT74
J 0
(-3540 1860);
DISPLAY 0.489362 (-3540 1860);
PAINT MONO (-3540 1860);
FORCEPROP 0 LASTPIN (-3550 1800) $PN BU73
J 0
(-3540 1810);
DISPLAY 0.489362 (-3540 1810);
PAINT MONO (-3540 1810);
FORCEPROP 0 LASTPIN (-3550 1750) $PN BU74
J 0
(-3540 1760);
DISPLAY 0.489362 (-3540 1760);
PAINT MONO (-3540 1760);
FORCEPROP 0 LASTPIN (-3550 1700) $PN BV72
J 0
(-3540 1710);
DISPLAY 0.489362 (-3540 1710);
PAINT MONO (-3540 1710);
FORCEPROP 0 LASTPIN (-3550 4300) $PN CB74
J 0
(-3540 4310);
DISPLAY 0.489362 (-3540 4310);
PAINT MONO (-3540 4310);
FORCEPROP 0 LASTPIN (-3550 4250) $PN CC73
J 0
(-3540 4260);
DISPLAY 0.489362 (-3540 4260);
PAINT MONO (-3540 4260);
FORCEPROP 0 LASTPIN (-3550 4200) $PN CC74
J 0
(-3540 4210);
DISPLAY 0.489362 (-3540 4210);
PAINT MONO (-3540 4210);
FORCEPROP 0 LASTPIN (-3550 4150) $PN CD72
J 0
(-3540 4160);
DISPLAY 0.489362 (-3540 4160);
PAINT MONO (-3540 4160);
FORCEPROP 0 LASTPIN (-3550 4100) $PN CF74
J 0
(-3540 4110);
DISPLAY 0.489362 (-3540 4110);
PAINT MONO (-3540 4110);
FORCEPROP 0 LASTPIN (-3550 4050) $PN CG73
J 0
(-3540 4060);
DISPLAY 0.489362 (-3540 4060);
PAINT MONO (-3540 4060);
FORCEPROP 0 LASTPIN (-3550 4000) $PN CG74
J 0
(-3540 4010);
DISPLAY 0.489362 (-3540 4010);
PAINT MONO (-3540 4010);
FORCEPROP 0 LASTPIN (-3550 3950) $PN CH72
J 0
(-3540 3960);
DISPLAY 0.489362 (-3540 3960);
PAINT MONO (-3540 3960);
FORCEPROP 0 LASTPIN (-3550 3850) $PN CH74
J 0
(-3540 3860);
DISPLAY 0.489362 (-3540 3860);
PAINT MONO (-3540 3860);
FORCEPROP 0 LASTPIN (-3550 3800) $PN CJ73
J 0
(-3540 3810);
DISPLAY 0.489362 (-3540 3810);
PAINT MONO (-3540 3810);
FORCEPROP 0 LASTPIN (-3550 3750) $PN CJ74
J 0
(-3540 3760);
DISPLAY 0.489362 (-3540 3760);
PAINT MONO (-3540 3760);
FORCEPROP 0 LASTPIN (-3550 3700) $PN CK72
J 0
(-3540 3710);
DISPLAY 0.489362 (-3540 3710);
PAINT MONO (-3540 3710);
FORCEPROP 0 LASTPIN (-3550 3650) $PN CM74
J 0
(-3540 3660);
DISPLAY 0.489362 (-3540 3660);
PAINT MONO (-3540 3660);
FORCEPROP 0 LASTPIN (-3550 3600) $PN CN73
J 0
(-3540 3610);
DISPLAY 0.489362 (-3540 3610);
PAINT MONO (-3540 3610);
FORCEPROP 0 LASTPIN (-3550 3550) $PN CN74
J 0
(-3540 3560);
DISPLAY 0.489362 (-3540 3560);
PAINT MONO (-3540 3560);
FORCEPROP 0 LASTPIN (-3550 3500) $PN CP72
J 0
(-3540 3510);
DISPLAY 0.489362 (-3540 3510);
PAINT MONO (-3540 3510);
FORCEPROP 0 LASTPIN (-3550 3400) $PN CP74
J 0
(-3540 3410);
DISPLAY 0.489362 (-3540 3410);
PAINT MONO (-3540 3410);
FORCEPROP 0 LASTPIN (-3550 3350) $PN CR73
J 0
(-3540 3360);
DISPLAY 0.489362 (-3540 3360);
PAINT MONO (-3540 3360);
FORCEPROP 0 LASTPIN (-3550 3300) $PN CR74
J 0
(-3540 3310);
DISPLAY 0.489362 (-3540 3310);
PAINT MONO (-3540 3310);
FORCEPROP 0 LASTPIN (-3550 3250) $PN CT72
J 0
(-3540 3260);
DISPLAY 0.489362 (-3540 3260);
PAINT MONO (-3540 3260);
FORCEPROP 0 LASTPIN (-3550 3200) $PN CV74
J 0
(-3540 3210);
DISPLAY 0.489362 (-3540 3210);
PAINT MONO (-3540 3210);
FORCEPROP 0 LASTPIN (-3550 3150) $PN CW73
J 0
(-3540 3160);
DISPLAY 0.489362 (-3540 3160);
PAINT MONO (-3540 3160);
FORCEPROP 0 LASTPIN (-3550 3100) $PN CW74
J 0
(-3540 3110);
DISPLAY 0.489362 (-3540 3110);
PAINT MONO (-3540 3110);
FORCEPROP 0 LASTPIN (-3550 3050) $PN CY72
J 0
(-3540 3060);
DISPLAY 0.489362 (-3540 3060);
PAINT MONO (-3540 3060);
FORCEPROP 0 LASTPIN (-3550 2950) $PN CY74
J 0
(-3540 2960);
DISPLAY 0.489362 (-3540 2960);
PAINT MONO (-3540 2960);
FORCEPROP 0 LASTPIN (-3550 2900) $PN DA73
J 0
(-3540 2910);
DISPLAY 0.489362 (-3540 2910);
PAINT MONO (-3540 2910);
FORCEPROP 0 LASTPIN (-3550 2850) $PN DA74
J 0
(-3540 2860);
DISPLAY 0.489362 (-3540 2860);
PAINT MONO (-3540 2860);
FORCEPROP 0 LASTPIN (-3550 2800) $PN DB72
J 0
(-3540 2810);
DISPLAY 0.489362 (-3540 2810);
PAINT MONO (-3540 2810);
FORCEPROP 0 LASTPIN (-3550 2750) $PN DD74
J 0
(-3540 2760);
DISPLAY 0.489362 (-3540 2760);
PAINT MONO (-3540 2760);
FORCEPROP 0 LASTPIN (-3550 2700) $PN DE73
J 0
(-3540 2710);
DISPLAY 0.489362 (-3540 2710);
PAINT MONO (-3540 2710);
FORCEPROP 0 LASTPIN (-3550 2650) $PN DE74
J 0
(-3540 2660);
DISPLAY 0.489362 (-3540 2660);
PAINT MONO (-3540 2660);
FORCEPROP 0 LASTPIN (-3550 2600) $PN DF74
J 0
(-3540 2610);
DISPLAY 0.489362 (-3540 2610);
PAINT MONO (-3540 2610);
FORCEPROP 0 LASTPIN (-5150 5050) $PN CD74
J 2
(-5160 5060);
DISPLAY 0.489362 (-5160 5060);
PAINT MONO (-5160 5060);
FORCEPROP 0 LASTPIN (-5150 4950) $PN CK74
J 2
(-5160 4960);
DISPLAY 0.489362 (-5160 4960);
PAINT MONO (-5160 4960);
FORCEPROP 0 LASTPIN (-5150 4850) $PN CT74
J 2
(-5160 4860);
DISPLAY 0.489362 (-5160 4860);
PAINT MONO (-5160 4860);
FORCEPROP 0 LASTPIN (-5150 4750) $PN DB74
J 2
(-5160 4760);
DISPLAY 0.489362 (-5160 4760);
PAINT MONO (-5160 4760);
FORCEPROP 0 LASTPIN (-5150 4650) $PN BY72
J 2
(-5160 4660);
DISPLAY 0.489362 (-5160 4660);
PAINT MONO (-5160 4660);
FORCEPROP 0 LASTPIN (-5150 4550) $PN CF72
J 2
(-5160 4560);
DISPLAY 0.489362 (-5160 4560);
PAINT MONO (-5160 4560);
FORCEPROP 0 LASTPIN (-5150 4450) $PN CM72
J 2
(-5160 4460);
DISPLAY 0.489362 (-5160 4460);
PAINT MONO (-5160 4460);
FORCEPROP 0 LASTPIN (-5150 4350) $PN CV72
J 2
(-5160 4360);
DISPLAY 0.489362 (-5160 4360);
PAINT MONO (-5160 4360);
FORCEPROP 0 LASTPIN (-5150 4250) $PN DD72
J 2
(-5160 4260);
DISPLAY 0.489362 (-5160 4260);
PAINT MONO (-5160 4260);
FORCEPROP 0 LASTPIN (-5150 4150) $PN BV74
J 2
(-5160 4160);
DISPLAY 0.489362 (-5160 4160);
PAINT MONO (-5160 4160);
FORCEPROP 0 LASTPIN (-5150 5000) $PN CE74
J 2
(-5160 5010);
DISPLAY 0.489362 (-5160 5010);
PAINT MONO (-5160 5010);
FORCEPROP 0 LASTPIN (-5150 4900) $PN CL74
J 2
(-5160 4910);
DISPLAY 0.489362 (-5160 4910);
PAINT MONO (-5160 4910);
FORCEPROP 0 LASTPIN (-5150 4800) $PN CU74
J 2
(-5160 4810);
DISPLAY 0.489362 (-5160 4810);
PAINT MONO (-5160 4810);
FORCEPROP 0 LASTPIN (-5150 4700) $PN DC74
J 2
(-5160 4710);
DISPLAY 0.489362 (-5160 4710);
PAINT MONO (-5160 4710);
FORCEPROP 0 LASTPIN (-5150 4600) $PN BW73
J 2
(-5160 4610);
DISPLAY 0.489362 (-5160 4610);
PAINT MONO (-5160 4610);
FORCEPROP 0 LASTPIN (-5150 4500) $PN CE73
J 2
(-5160 4510);
DISPLAY 0.489362 (-5160 4510);
PAINT MONO (-5160 4510);
FORCEPROP 0 LASTPIN (-5150 4400) $PN CL73
J 2
(-5160 4410);
DISPLAY 0.489362 (-5160 4410);
PAINT MONO (-5160 4410);
FORCEPROP 0 LASTPIN (-5150 4300) $PN CU73
J 2
(-5160 4310);
DISPLAY 0.489362 (-5160 4310);
PAINT MONO (-5160 4310);
FORCEPROP 0 LASTPIN (-5150 4200) $PN DC73
J 2
(-5160 4210);
DISPLAY 0.489362 (-5160 4210);
PAINT MONO (-5160 4210);
FORCEPROP 0 LASTPIN (-5150 4100) $PN BW74
J 2
(-5160 4110);
DISPLAY 0.489362 (-5160 4110);
PAINT MONO (-5160 4110);
FORCEPROP 0 LASTPIN (-5150 2350) $PN BL74
J 2
(-5160 2360);
DISPLAY 0.489362 (-5160 2360);
PAINT MONO (-5160 2360);
FORCEPROP 0 LASTPIN (-5150 1300) $PN BF72
J 2
(-5160 1310);
DISPLAY 0.489362 (-5160 1310);
PAINT MONO (-5160 1310);
FORCEPROP 0 LASTPIN (-5150 1250) $PN C60
J 2
(-5160 1260);
DISPLAY 0.489362 (-5160 1260);
PAINT MONO (-5160 1260);
FORCEPROP 2 LAST PART_TYPE SMLF
J 0
(-5000 6400);
DISPLAY 1.021277 (-5000 6400);
FORCEPROP 1 LAST MATERIAL IO
J 0
(-4995 6232);
DISPLAY 0.489362 (-4995 6232);
PAINT SKYBLUE (-4995 6232);
FORCEPROP 2 LAST VALUE SOCKET6096_13568-001
J 0
(-5000 6300);
DISPLAY 0.489362 (-5000 6300);
PAINT SKYBLUE (-5000 6300);
FORCEPROP 1 LAST PART_NUMBER DGA^6000030
J 0
(-4995 6359);
DISPLAY 0.489362 (-4995 6359);
PAINT SKYBLUE (-4995 6359);
FORCEPROP 2 LAST CDS_LIB pure_quanta
J 0
(-4350 3700);
DISPLAY INVISIBLE (-4350 3700);
FORCEPROP 1 LAST NEEDS_NO_SIZE TRUE
J 0
(-4350 3700);
DISPLAY 0.723404 (-4350 3700);
PAINT GREEN (-4350 3700);
DISPLAY INVISIBLE (-4350 3700);
FORCEPROP 1 LAST CDS_LMAN_SYM_OUTLINE -650,2500,650,-2500
J 0
(-4350 3700);
DISPLAY 0.468085 (-4350 3700);
PAINT GREEN (-4350 3700);
DISPLAY INVISIBLE (-4350 3700);
FORCEPROP 1 LAST PATH I200
J 0
(-4350 3700);
DISPLAY 0.723404 (-4350 3700);
PAINT GREEN (-4350 3700);
DISPLAY INVISIBLE (-4350 3700);
FORCEADD OFFPAGE..3
(-2300 6125);
FORCEPROP 2 LAST $XR0 85 
J 0
(-2086 6125);
DISPLAY 0.638298 (-2086 6125);
PAINT MONO (-2086 6125);
FORCEPROP 2 LAST PATH I682
J 0
(-2075 6175);
DISPLAY 1.021277 (-2075 6175);
DISPLAY INVISIBLE (-2075 6175);
FORCEPROP 1 LAST COMMENT_BODY TRUE
J 0
(-2350 6025);
DISPLAY 0.872340 (-2350 6025);
PAINT GREEN (-2350 6025);
DISPLAY INVISIBLE (-2350 6025);
FORCEPROP 1 LAST OFFPAGE TRUE
J 0
(-1975 6000);
DISPLAY 0.872340 (-1975 6000);
PAINT GREEN (-1975 6000);
DISPLAY INVISIBLE (-1975 6000);
FORCEPROP 2 LAST CDS_LIB mstr_standard
J 0
(-2300 6125);
DISPLAY INVISIBLE (-2300 6125);
FORCEADD TAP..1
(-3025 6100);
FORCEPROP 3 LASTPIN (-3075 6100) SIG_NAME M_A_CPU0_SA_DQ<0>
J 0
(-3065 6110);
DISPLAY 0.659574 (-3065 6110);
PAINT MONO (-3065 6110);
DISPLAY INVISIBLE (-3065 6110);
FORCEPROP 1 LASTPIN (-3075 6100) BN 0
J 0
(-3087 6108);
DISPLAY 0.489362 (-3087 6108);
PAINT MONO (-3087 6108);
FORCEPROP 2 LAST CDS_LIB mstr_standard
J 0
(-3025 6100);
DISPLAY INVISIBLE (-3025 6100);
FORCEPROP 1 LAST BODY_TYPE PLUMBING
J 0
(-3025 6150);
DISPLAY 0.872340 (-3025 6150);
PAINT GREEN (-3025 6150);
DISPLAY INVISIBLE (-3025 6150);
FORCEPROP 1 LAST HDL_TAP TRUE
J 0
(-2700 5975);
DISPLAY 0.872340 (-2700 5975);
DISPLAY INVISIBLE (-2700 5975);
FORCEPROP 1 LAST PATH I683
J 0
(-3027 6100);
DISPLAY 0.872340 (-3027 6100);
PAINT GREEN (-3027 6100);
DISPLAY INVISIBLE (-3027 6100);
FORCEADD TAP..1
(-3025 5950);
FORCEPROP 3 LASTPIN (-3075 5950) SIG_NAME M_A_CPU0_SA_DQ<3>
J 0
(-3065 5960);
DISPLAY 0.659574 (-3065 5960);
PAINT MONO (-3065 5960);
DISPLAY INVISIBLE (-3065 5960);
FORCEPROP 1 LASTPIN (-3075 5950) BN 3
J 0
(-3087 5958);
DISPLAY 0.489362 (-3087 5958);
PAINT MONO (-3087 5958);
FORCEPROP 2 LAST CDS_LIB mstr_standard
J 0
(-3025 5950);
DISPLAY INVISIBLE (-3025 5950);
FORCEPROP 1 LAST BODY_TYPE PLUMBING
J 0
(-3025 6000);
DISPLAY 0.872340 (-3025 6000);
PAINT GREEN (-3025 6000);
DISPLAY INVISIBLE (-3025 6000);
FORCEPROP 1 LAST HDL_TAP TRUE
J 0
(-2700 5825);
DISPLAY 0.872340 (-2700 5825);
DISPLAY INVISIBLE (-2700 5825);
FORCEPROP 1 LAST PATH I684
J 0
(-3027 5950);
DISPLAY 0.872340 (-3027 5950);
PAINT GREEN (-3027 5950);
DISPLAY INVISIBLE (-3027 5950);
FORCEADD TAP..1
(-3025 6000);
FORCEPROP 3 LASTPIN (-3075 6000) SIG_NAME M_A_CPU0_SA_DQ<2>
J 0
(-3065 6010);
DISPLAY 0.659574 (-3065 6010);
PAINT MONO (-3065 6010);
DISPLAY INVISIBLE (-3065 6010);
FORCEPROP 1 LASTPIN (-3075 6000) BN 2
J 0
(-3087 6008);
DISPLAY 0.489362 (-3087 6008);
PAINT MONO (-3087 6008);
FORCEPROP 2 LAST CDS_LIB mstr_standard
J 0
(-3025 6000);
DISPLAY INVISIBLE (-3025 6000);
FORCEPROP 1 LAST BODY_TYPE PLUMBING
J 0
(-3025 6050);
DISPLAY 0.872340 (-3025 6050);
PAINT GREEN (-3025 6050);
DISPLAY INVISIBLE (-3025 6050);
FORCEPROP 1 LAST HDL_TAP TRUE
J 0
(-2700 5875);
DISPLAY 0.872340 (-2700 5875);
DISPLAY INVISIBLE (-2700 5875);
FORCEPROP 1 LAST PATH I685
J 0
(-3027 6000);
DISPLAY 0.872340 (-3027 6000);
PAINT GREEN (-3027 6000);
DISPLAY INVISIBLE (-3027 6000);
FORCEADD TAP..1
(-3025 6050);
FORCEPROP 3 LASTPIN (-3075 6050) SIG_NAME M_A_CPU0_SA_DQ<1>
J 0
(-3065 6060);
DISPLAY 0.659574 (-3065 6060);
PAINT MONO (-3065 6060);
DISPLAY INVISIBLE (-3065 6060);
FORCEPROP 1 LASTPIN (-3075 6050) BN 1
J 0
(-3087 6058);
DISPLAY 0.489362 (-3087 6058);
PAINT MONO (-3087 6058);
FORCEPROP 2 LAST CDS_LIB mstr_standard
J 0
(-3025 6050);
DISPLAY INVISIBLE (-3025 6050);
FORCEPROP 1 LAST BODY_TYPE PLUMBING
J 0
(-3025 6100);
DISPLAY 0.872340 (-3025 6100);
PAINT GREEN (-3025 6100);
DISPLAY INVISIBLE (-3025 6100);
FORCEPROP 1 LAST HDL_TAP TRUE
J 0
(-2700 5925);
DISPLAY 0.872340 (-2700 5925);
DISPLAY INVISIBLE (-2700 5925);
FORCEPROP 1 LAST PATH I686
J 0
(-3027 6050);
DISPLAY 0.872340 (-3027 6050);
PAINT GREEN (-3027 6050);
DISPLAY INVISIBLE (-3027 6050);
FORCEADD TAP..1
(-3025 5900);
FORCEPROP 3 LASTPIN (-3075 5900) SIG_NAME M_A_CPU0_SA_DQ<4>
J 0
(-3065 5910);
DISPLAY 0.659574 (-3065 5910);
PAINT MONO (-3065 5910);
DISPLAY INVISIBLE (-3065 5910);
FORCEPROP 1 LASTPIN (-3075 5900) BN 4
J 0
(-3087 5908);
DISPLAY 0.489362 (-3087 5908);
PAINT MONO (-3087 5908);
FORCEPROP 2 LAST CDS_LIB mstr_standard
J 0
(-3025 5900);
DISPLAY INVISIBLE (-3025 5900);
FORCEPROP 1 LAST BODY_TYPE PLUMBING
J 0
(-3025 5950);
DISPLAY 0.872340 (-3025 5950);
PAINT GREEN (-3025 5950);
DISPLAY INVISIBLE (-3025 5950);
FORCEPROP 1 LAST HDL_TAP TRUE
J 0
(-2700 5775);
DISPLAY 0.872340 (-2700 5775);
DISPLAY INVISIBLE (-2700 5775);
FORCEPROP 1 LAST PATH I687
J 0
(-3027 5900);
DISPLAY 0.872340 (-3027 5900);
PAINT GREEN (-3027 5900);
DISPLAY INVISIBLE (-3027 5900);
FORCEADD TAP..1
(-3025 5850);
FORCEPROP 3 LASTPIN (-3075 5850) SIG_NAME M_A_CPU0_SA_DQ<5>
J 0
(-3065 5860);
DISPLAY 0.659574 (-3065 5860);
PAINT MONO (-3065 5860);
DISPLAY INVISIBLE (-3065 5860);
FORCEPROP 1 LASTPIN (-3075 5850) BN 5
J 0
(-3087 5858);
DISPLAY 0.489362 (-3087 5858);
PAINT MONO (-3087 5858);
FORCEPROP 2 LAST CDS_LIB mstr_standard
J 0
(-3025 5850);
DISPLAY INVISIBLE (-3025 5850);
FORCEPROP 1 LAST BODY_TYPE PLUMBING
J 0
(-3025 5900);
DISPLAY 0.872340 (-3025 5900);
PAINT GREEN (-3025 5900);
DISPLAY INVISIBLE (-3025 5900);
FORCEPROP 1 LAST HDL_TAP TRUE
J 0
(-2700 5725);
DISPLAY 0.872340 (-2700 5725);
DISPLAY INVISIBLE (-2700 5725);
FORCEPROP 1 LAST PATH I688
J 0
(-3027 5850);
DISPLAY 0.872340 (-3027 5850);
PAINT GREEN (-3027 5850);
DISPLAY INVISIBLE (-3027 5850);
FORCEADD TAP..1
(-3025 5650);
FORCEPROP 3 LASTPIN (-3075 5650) SIG_NAME M_A_CPU0_SA_DQ<8>
J 0
(-3065 5660);
DISPLAY 0.659574 (-3065 5660);
PAINT MONO (-3065 5660);
DISPLAY INVISIBLE (-3065 5660);
FORCEPROP 1 LASTPIN (-3075 5650) BN 8
J 0
(-3087 5658);
DISPLAY 0.489362 (-3087 5658);
PAINT MONO (-3087 5658);
FORCEPROP 2 LAST CDS_LIB mstr_standard
J 0
(-3025 5650);
DISPLAY INVISIBLE (-3025 5650);
FORCEPROP 1 LAST BODY_TYPE PLUMBING
J 0
(-3025 5700);
DISPLAY 0.872340 (-3025 5700);
PAINT GREEN (-3025 5700);
DISPLAY INVISIBLE (-3025 5700);
FORCEPROP 1 LAST HDL_TAP TRUE
J 0
(-2700 5525);
DISPLAY 0.872340 (-2700 5525);
DISPLAY INVISIBLE (-2700 5525);
FORCEPROP 1 LAST PATH I689
J 0
(-3027 5650);
DISPLAY 0.872340 (-3027 5650);
PAINT GREEN (-3027 5650);
DISPLAY INVISIBLE (-3027 5650);
FORCEADD TAP..1
(-3025 5750);
FORCEPROP 3 LASTPIN (-3075 5750) SIG_NAME M_A_CPU0_SA_DQ<7>
J 0
(-3065 5760);
DISPLAY 0.659574 (-3065 5760);
PAINT MONO (-3065 5760);
DISPLAY INVISIBLE (-3065 5760);
FORCEPROP 1 LASTPIN (-3075 5750) BN 7
J 0
(-3087 5758);
DISPLAY 0.489362 (-3087 5758);
PAINT MONO (-3087 5758);
FORCEPROP 2 LAST CDS_LIB mstr_standard
J 0
(-3025 5750);
DISPLAY INVISIBLE (-3025 5750);
FORCEPROP 1 LAST BODY_TYPE PLUMBING
J 0
(-3025 5800);
DISPLAY 0.872340 (-3025 5800);
PAINT GREEN (-3025 5800);
DISPLAY INVISIBLE (-3025 5800);
FORCEPROP 1 LAST HDL_TAP TRUE
J 0
(-2700 5625);
DISPLAY 0.872340 (-2700 5625);
DISPLAY INVISIBLE (-2700 5625);
FORCEPROP 1 LAST PATH I690
J 0
(-3027 5750);
DISPLAY 0.872340 (-3027 5750);
PAINT GREEN (-3027 5750);
DISPLAY INVISIBLE (-3027 5750);
FORCEADD TAP..1
(-3025 5800);
FORCEPROP 3 LASTPIN (-3075 5800) SIG_NAME M_A_CPU0_SA_DQ<6>
J 0
(-3065 5810);
DISPLAY 0.659574 (-3065 5810);
PAINT MONO (-3065 5810);
DISPLAY INVISIBLE (-3065 5810);
FORCEPROP 1 LASTPIN (-3075 5800) BN 6
J 0
(-3087 5808);
DISPLAY 0.489362 (-3087 5808);
PAINT MONO (-3087 5808);
FORCEPROP 2 LAST CDS_LIB mstr_standard
J 0
(-3025 5800);
DISPLAY INVISIBLE (-3025 5800);
FORCEPROP 1 LAST BODY_TYPE PLUMBING
J 0
(-3025 5850);
DISPLAY 0.872340 (-3025 5850);
PAINT GREEN (-3025 5850);
DISPLAY INVISIBLE (-3025 5850);
FORCEPROP 1 LAST HDL_TAP TRUE
J 0
(-2700 5675);
DISPLAY 0.872340 (-2700 5675);
DISPLAY INVISIBLE (-2700 5675);
FORCEPROP 1 LAST PATH I691
J 0
(-3027 5800);
DISPLAY 0.872340 (-3027 5800);
PAINT GREEN (-3027 5800);
DISPLAY INVISIBLE (-3027 5800);
FORCEADD TAP..1
(-3025 5600);
FORCEPROP 3 LASTPIN (-3075 5600) SIG_NAME M_A_CPU0_SA_DQ<9>
J 0
(-3065 5610);
DISPLAY 0.659574 (-3065 5610);
PAINT MONO (-3065 5610);
DISPLAY INVISIBLE (-3065 5610);
FORCEPROP 1 LASTPIN (-3075 5600) BN 9
J 0
(-3087 5608);
DISPLAY 0.489362 (-3087 5608);
PAINT MONO (-3087 5608);
FORCEPROP 2 LAST CDS_LIB mstr_standard
J 0
(-3025 5600);
DISPLAY INVISIBLE (-3025 5600);
FORCEPROP 1 LAST BODY_TYPE PLUMBING
J 0
(-3025 5650);
DISPLAY 0.872340 (-3025 5650);
PAINT GREEN (-3025 5650);
DISPLAY INVISIBLE (-3025 5650);
FORCEPROP 1 LAST HDL_TAP TRUE
J 0
(-2700 5475);
DISPLAY 0.872340 (-2700 5475);
DISPLAY INVISIBLE (-2700 5475);
FORCEPROP 1 LAST PATH I692
J 0
(-3027 5600);
DISPLAY 0.872340 (-3027 5600);
PAINT GREEN (-3027 5600);
DISPLAY INVISIBLE (-3027 5600);
FORCEADD TAP..1
(-3025 5400);
FORCEPROP 3 LASTPIN (-3075 5400) SIG_NAME M_A_CPU0_SA_DQ<13>
J 0
(-3065 5410);
DISPLAY 0.659574 (-3065 5410);
PAINT MONO (-3065 5410);
DISPLAY INVISIBLE (-3065 5410);
FORCEPROP 1 LASTPIN (-3075 5400) BN 13
J 0
(-3087 5408);
DISPLAY 0.489362 (-3087 5408);
PAINT MONO (-3087 5408);
FORCEPROP 2 LAST CDS_LIB mstr_standard
J 0
(-3025 5400);
DISPLAY INVISIBLE (-3025 5400);
FORCEPROP 1 LAST BODY_TYPE PLUMBING
J 0
(-3025 5450);
DISPLAY 0.872340 (-3025 5450);
PAINT GREEN (-3025 5450);
DISPLAY INVISIBLE (-3025 5450);
FORCEPROP 1 LAST HDL_TAP TRUE
J 0
(-2700 5275);
DISPLAY 0.872340 (-2700 5275);
DISPLAY INVISIBLE (-2700 5275);
FORCEPROP 1 LAST PATH I693
J 0
(-3027 5400);
DISPLAY 0.872340 (-3027 5400);
PAINT GREEN (-3027 5400);
DISPLAY INVISIBLE (-3027 5400);
FORCEADD TAP..1
(-3025 5450);
FORCEPROP 3 LASTPIN (-3075 5450) SIG_NAME M_A_CPU0_SA_DQ<12>
J 0
(-3065 5460);
DISPLAY 0.659574 (-3065 5460);
PAINT MONO (-3065 5460);
DISPLAY INVISIBLE (-3065 5460);
FORCEPROP 1 LASTPIN (-3075 5450) BN 12
J 0
(-3087 5458);
DISPLAY 0.489362 (-3087 5458);
PAINT MONO (-3087 5458);
FORCEPROP 2 LAST CDS_LIB mstr_standard
J 0
(-3025 5450);
DISPLAY INVISIBLE (-3025 5450);
FORCEPROP 1 LAST BODY_TYPE PLUMBING
J 0
(-3025 5500);
DISPLAY 0.872340 (-3025 5500);
PAINT GREEN (-3025 5500);
DISPLAY INVISIBLE (-3025 5500);
FORCEPROP 1 LAST HDL_TAP TRUE
J 0
(-2700 5325);
DISPLAY 0.872340 (-2700 5325);
DISPLAY INVISIBLE (-2700 5325);
FORCEPROP 1 LAST PATH I694
J 0
(-3027 5450);
DISPLAY 0.872340 (-3027 5450);
PAINT GREEN (-3027 5450);
DISPLAY INVISIBLE (-3027 5450);
FORCEADD TAP..1
(-3025 5500);
FORCEPROP 3 LASTPIN (-3075 5500) SIG_NAME M_A_CPU0_SA_DQ<11>
J 0
(-3065 5510);
DISPLAY 0.659574 (-3065 5510);
PAINT MONO (-3065 5510);
DISPLAY INVISIBLE (-3065 5510);
FORCEPROP 1 LASTPIN (-3075 5500) BN 11
J 0
(-3087 5508);
DISPLAY 0.489362 (-3087 5508);
PAINT MONO (-3087 5508);
FORCEPROP 2 LAST CDS_LIB mstr_standard
J 0
(-3025 5500);
DISPLAY INVISIBLE (-3025 5500);
FORCEPROP 1 LAST BODY_TYPE PLUMBING
J 0
(-3025 5550);
DISPLAY 0.872340 (-3025 5550);
PAINT GREEN (-3025 5550);
DISPLAY INVISIBLE (-3025 5550);
FORCEPROP 1 LAST HDL_TAP TRUE
J 0
(-2700 5375);
DISPLAY 0.872340 (-2700 5375);
DISPLAY INVISIBLE (-2700 5375);
FORCEPROP 1 LAST PATH I695
J 0
(-3027 5500);
DISPLAY 0.872340 (-3027 5500);
PAINT GREEN (-3027 5500);
DISPLAY INVISIBLE (-3027 5500);
FORCEADD TAP..1
(-3025 5550);
FORCEPROP 3 LASTPIN (-3075 5550) SIG_NAME M_A_CPU0_SA_DQ<10>
J 0
(-3065 5560);
DISPLAY 0.659574 (-3065 5560);
PAINT MONO (-3065 5560);
DISPLAY INVISIBLE (-3065 5560);
FORCEPROP 1 LASTPIN (-3075 5550) BN 10
J 0
(-3087 5558);
DISPLAY 0.489362 (-3087 5558);
PAINT MONO (-3087 5558);
FORCEPROP 2 LAST CDS_LIB mstr_standard
J 0
(-3025 5550);
DISPLAY INVISIBLE (-3025 5550);
FORCEPROP 1 LAST BODY_TYPE PLUMBING
J 0
(-3025 5600);
DISPLAY 0.872340 (-3025 5600);
PAINT GREEN (-3025 5600);
DISPLAY INVISIBLE (-3025 5600);
FORCEPROP 1 LAST HDL_TAP TRUE
J 0
(-2700 5425);
DISPLAY 0.872340 (-2700 5425);
DISPLAY INVISIBLE (-2700 5425);
FORCEPROP 1 LAST PATH I696
J 0
(-3027 5550);
DISPLAY 0.872340 (-3027 5550);
PAINT GREEN (-3027 5550);
DISPLAY INVISIBLE (-3027 5550);
FORCEADD TAP..1
(-3025 5350);
FORCEPROP 3 LASTPIN (-3075 5350) SIG_NAME M_A_CPU0_SA_DQ<14>
J 0
(-3065 5360);
DISPLAY 0.659574 (-3065 5360);
PAINT MONO (-3065 5360);
DISPLAY INVISIBLE (-3065 5360);
FORCEPROP 1 LASTPIN (-3075 5350) BN 14
J 0
(-3087 5358);
DISPLAY 0.489362 (-3087 5358);
PAINT MONO (-3087 5358);
FORCEPROP 2 LAST CDS_LIB mstr_standard
J 0
(-3025 5350);
DISPLAY INVISIBLE (-3025 5350);
FORCEPROP 1 LAST BODY_TYPE PLUMBING
J 0
(-3025 5400);
DISPLAY 0.872340 (-3025 5400);
PAINT GREEN (-3025 5400);
DISPLAY INVISIBLE (-3025 5400);
FORCEPROP 1 LAST HDL_TAP TRUE
J 0
(-2700 5225);
DISPLAY 0.872340 (-2700 5225);
DISPLAY INVISIBLE (-2700 5225);
FORCEPROP 1 LAST PATH I697
J 0
(-3027 5350);
DISPLAY 0.872340 (-3027 5350);
PAINT GREEN (-3027 5350);
DISPLAY INVISIBLE (-3027 5350);
FORCEADD TAP..1
(-3025 5200);
FORCEPROP 3 LASTPIN (-3075 5200) SIG_NAME M_A_CPU0_SA_DQ<16>
J 0
(-3065 5210);
DISPLAY 0.659574 (-3065 5210);
PAINT MONO (-3065 5210);
DISPLAY INVISIBLE (-3065 5210);
FORCEPROP 1 LASTPIN (-3075 5200) BN 16
J 0
(-3087 5208);
DISPLAY 0.489362 (-3087 5208);
PAINT MONO (-3087 5208);
FORCEPROP 2 LAST CDS_LIB mstr_standard
J 0
(-3025 5200);
DISPLAY INVISIBLE (-3025 5200);
FORCEPROP 1 LAST BODY_TYPE PLUMBING
J 0
(-3025 5250);
DISPLAY 0.872340 (-3025 5250);
PAINT GREEN (-3025 5250);
DISPLAY INVISIBLE (-3025 5250);
FORCEPROP 1 LAST HDL_TAP TRUE
J 0
(-2700 5075);
DISPLAY 0.872340 (-2700 5075);
DISPLAY INVISIBLE (-2700 5075);
FORCEPROP 1 LAST PATH I698
J 0
(-3027 5200);
DISPLAY 0.872340 (-3027 5200);
PAINT GREEN (-3027 5200);
DISPLAY INVISIBLE (-3027 5200);
FORCEADD TAP..1
(-3025 5150);
FORCEPROP 3 LASTPIN (-3075 5150) SIG_NAME M_A_CPU0_SA_DQ<17>
J 0
(-3065 5160);
DISPLAY 0.659574 (-3065 5160);
PAINT MONO (-3065 5160);
DISPLAY INVISIBLE (-3065 5160);
FORCEPROP 1 LASTPIN (-3075 5150) BN 17
J 0
(-3087 5158);
DISPLAY 0.489362 (-3087 5158);
PAINT MONO (-3087 5158);
FORCEPROP 2 LAST CDS_LIB mstr_standard
J 0
(-3025 5150);
DISPLAY INVISIBLE (-3025 5150);
FORCEPROP 1 LAST BODY_TYPE PLUMBING
J 0
(-3025 5200);
DISPLAY 0.872340 (-3025 5200);
PAINT GREEN (-3025 5200);
DISPLAY INVISIBLE (-3025 5200);
FORCEPROP 1 LAST HDL_TAP TRUE
J 0
(-2700 5025);
DISPLAY 0.872340 (-2700 5025);
DISPLAY INVISIBLE (-2700 5025);
FORCEPROP 1 LAST PATH I699
J 0
(-3027 5150);
DISPLAY 0.872340 (-3027 5150);
PAINT GREEN (-3027 5150);
DISPLAY INVISIBLE (-3027 5150);
FORCEADD TAP..1
(-3025 5300);
FORCEPROP 3 LASTPIN (-3075 5300) SIG_NAME M_A_CPU0_SA_DQ<15>
J 0
(-3065 5310);
DISPLAY 0.659574 (-3065 5310);
PAINT MONO (-3065 5310);
DISPLAY INVISIBLE (-3065 5310);
FORCEPROP 1 LASTPIN (-3075 5300) BN 15
J 0
(-3087 5308);
DISPLAY 0.489362 (-3087 5308);
PAINT MONO (-3087 5308);
FORCEPROP 2 LAST CDS_LIB mstr_standard
J 0
(-3025 5300);
DISPLAY INVISIBLE (-3025 5300);
FORCEPROP 1 LAST BODY_TYPE PLUMBING
J 0
(-3025 5350);
DISPLAY 0.872340 (-3025 5350);
PAINT GREEN (-3025 5350);
DISPLAY INVISIBLE (-3025 5350);
FORCEPROP 1 LAST HDL_TAP TRUE
J 0
(-2700 5175);
DISPLAY 0.872340 (-2700 5175);
DISPLAY INVISIBLE (-2700 5175);
FORCEPROP 1 LAST PATH I700
J 0
(-3027 5300);
DISPLAY 0.872340 (-3027 5300);
PAINT GREEN (-3027 5300);
DISPLAY INVISIBLE (-3027 5300);
FORCEADD TAP..1
(-3025 5050);
FORCEPROP 3 LASTPIN (-3075 5050) SIG_NAME M_A_CPU0_SA_DQ<19>
J 0
(-3065 5060);
DISPLAY 0.659574 (-3065 5060);
PAINT MONO (-3065 5060);
DISPLAY INVISIBLE (-3065 5060);
FORCEPROP 1 LASTPIN (-3075 5050) BN 19
J 0
(-3087 5058);
DISPLAY 0.489362 (-3087 5058);
PAINT MONO (-3087 5058);
FORCEPROP 2 LAST CDS_LIB mstr_standard
J 0
(-3025 5050);
DISPLAY INVISIBLE (-3025 5050);
FORCEPROP 1 LAST BODY_TYPE PLUMBING
J 0
(-3025 5100);
DISPLAY 0.872340 (-3025 5100);
PAINT GREEN (-3025 5100);
DISPLAY INVISIBLE (-3025 5100);
FORCEPROP 1 LAST HDL_TAP TRUE
J 0
(-2700 4925);
DISPLAY 0.872340 (-2700 4925);
DISPLAY INVISIBLE (-2700 4925);
FORCEPROP 1 LAST PATH I701
J 0
(-3027 5050);
DISPLAY 0.872340 (-3027 5050);
PAINT GREEN (-3027 5050);
DISPLAY INVISIBLE (-3027 5050);
FORCEADD TAP..1
(-3025 5100);
FORCEPROP 3 LASTPIN (-3075 5100) SIG_NAME M_A_CPU0_SA_DQ<18>
J 0
(-3065 5110);
DISPLAY 0.659574 (-3065 5110);
PAINT MONO (-3065 5110);
DISPLAY INVISIBLE (-3065 5110);
FORCEPROP 1 LASTPIN (-3075 5100) BN 18
J 0
(-3087 5108);
DISPLAY 0.489362 (-3087 5108);
PAINT MONO (-3087 5108);
FORCEPROP 2 LAST CDS_LIB mstr_standard
J 0
(-3025 5100);
DISPLAY INVISIBLE (-3025 5100);
FORCEPROP 1 LAST BODY_TYPE PLUMBING
J 0
(-3025 5150);
DISPLAY 0.872340 (-3025 5150);
PAINT GREEN (-3025 5150);
DISPLAY INVISIBLE (-3025 5150);
FORCEPROP 1 LAST HDL_TAP TRUE
J 0
(-2700 4975);
DISPLAY 0.872340 (-2700 4975);
DISPLAY INVISIBLE (-2700 4975);
FORCEPROP 1 LAST PATH I702
J 0
(-3027 5100);
DISPLAY 0.872340 (-3027 5100);
PAINT GREEN (-3027 5100);
DISPLAY INVISIBLE (-3027 5100);
FORCEADD OFFPAGE..3
(-2300 4325);
FORCEPROP 2 LAST $XR0 85 
J 0
(-2086 4325);
DISPLAY 0.638298 (-2086 4325);
PAINT MONO (-2086 4325);
FORCEPROP 2 LAST PATH I703
J 0
(-2075 4375);
DISPLAY 1.021277 (-2075 4375);
DISPLAY INVISIBLE (-2075 4375);
FORCEPROP 1 LAST COMMENT_BODY TRUE
J 0
(-2350 4225);
DISPLAY 0.872340 (-2350 4225);
PAINT GREEN (-2350 4225);
DISPLAY INVISIBLE (-2350 4225);
FORCEPROP 1 LAST OFFPAGE TRUE
J 0
(-1975 4200);
DISPLAY 0.872340 (-1975 4200);
PAINT GREEN (-1975 4200);
DISPLAY INVISIBLE (-1975 4200);
FORCEPROP 2 LAST CDS_LIB mstr_standard
J 0
(-2300 4325);
DISPLAY INVISIBLE (-2300 4325);
FORCEADD TAP..1
(-3025 4950);
FORCEPROP 3 LASTPIN (-3075 4950) SIG_NAME M_A_CPU0_SA_DQ<21>
J 0
(-3065 4960);
DISPLAY 0.659574 (-3065 4960);
PAINT MONO (-3065 4960);
DISPLAY INVISIBLE (-3065 4960);
FORCEPROP 1 LASTPIN (-3075 4950) BN 21
J 0
(-3087 4958);
DISPLAY 0.489362 (-3087 4958);
PAINT MONO (-3087 4958);
FORCEPROP 2 LAST CDS_LIB mstr_standard
J 0
(-3025 4950);
DISPLAY INVISIBLE (-3025 4950);
FORCEPROP 1 LAST BODY_TYPE PLUMBING
J 0
(-3025 5000);
DISPLAY 0.872340 (-3025 5000);
PAINT GREEN (-3025 5000);
DISPLAY INVISIBLE (-3025 5000);
FORCEPROP 1 LAST HDL_TAP TRUE
J 0
(-2700 4825);
DISPLAY 0.872340 (-2700 4825);
DISPLAY INVISIBLE (-2700 4825);
FORCEPROP 1 LAST PATH I704
J 0
(-3027 4950);
DISPLAY 0.872340 (-3027 4950);
PAINT GREEN (-3027 4950);
DISPLAY INVISIBLE (-3027 4950);
FORCEADD TAP..1
(-3025 4900);
FORCEPROP 3 LASTPIN (-3075 4900) SIG_NAME M_A_CPU0_SA_DQ<22>
J 0
(-3065 4910);
DISPLAY 0.659574 (-3065 4910);
PAINT MONO (-3065 4910);
DISPLAY INVISIBLE (-3065 4910);
FORCEPROP 1 LASTPIN (-3075 4900) BN 22
J 0
(-3087 4908);
DISPLAY 0.489362 (-3087 4908);
PAINT MONO (-3087 4908);
FORCEPROP 2 LAST CDS_LIB mstr_standard
J 0
(-3025 4900);
DISPLAY INVISIBLE (-3025 4900);
FORCEPROP 1 LAST BODY_TYPE PLUMBING
J 0
(-3025 4950);
DISPLAY 0.872340 (-3025 4950);
PAINT GREEN (-3025 4950);
DISPLAY INVISIBLE (-3025 4950);
FORCEPROP 1 LAST HDL_TAP TRUE
J 0
(-2700 4775);
DISPLAY 0.872340 (-2700 4775);
DISPLAY INVISIBLE (-2700 4775);
FORCEPROP 1 LAST PATH I705
J 0
(-3027 4900);
DISPLAY 0.872340 (-3027 4900);
PAINT GREEN (-3027 4900);
DISPLAY INVISIBLE (-3027 4900);
FORCEADD TAP..1
(-3025 5000);
FORCEPROP 3 LASTPIN (-3075 5000) SIG_NAME M_A_CPU0_SA_DQ<20>
J 0
(-3065 5010);
DISPLAY 0.659574 (-3065 5010);
PAINT MONO (-3065 5010);
DISPLAY INVISIBLE (-3065 5010);
FORCEPROP 1 LASTPIN (-3075 5000) BN 20
J 0
(-3087 5008);
DISPLAY 0.489362 (-3087 5008);
PAINT MONO (-3087 5008);
FORCEPROP 2 LAST CDS_LIB mstr_standard
J 0
(-3025 5000);
DISPLAY INVISIBLE (-3025 5000);
FORCEPROP 1 LAST BODY_TYPE PLUMBING
J 0
(-3025 5050);
DISPLAY 0.872340 (-3025 5050);
PAINT GREEN (-3025 5050);
DISPLAY INVISIBLE (-3025 5050);
FORCEPROP 1 LAST HDL_TAP TRUE
J 0
(-2700 4875);
DISPLAY 0.872340 (-2700 4875);
DISPLAY INVISIBLE (-2700 4875);
FORCEPROP 1 LAST PATH I706
J 0
(-3027 5000);
DISPLAY 0.872340 (-3027 5000);
PAINT GREEN (-3027 5000);
DISPLAY INVISIBLE (-3027 5000);
FORCEADD TAP..1
(-3025 4850);
FORCEPROP 3 LASTPIN (-3075 4850) SIG_NAME M_A_CPU0_SA_DQ<23>
J 0
(-3065 4860);
DISPLAY 0.659574 (-3065 4860);
PAINT MONO (-3065 4860);
DISPLAY INVISIBLE (-3065 4860);
FORCEPROP 1 LASTPIN (-3075 4850) BN 23
J 0
(-3087 4858);
DISPLAY 0.489362 (-3087 4858);
PAINT MONO (-3087 4858);
FORCEPROP 2 LAST CDS_LIB mstr_standard
J 0
(-3025 4850);
DISPLAY INVISIBLE (-3025 4850);
FORCEPROP 1 LAST BODY_TYPE PLUMBING
J 0
(-3025 4900);
DISPLAY 0.872340 (-3025 4900);
PAINT GREEN (-3025 4900);
DISPLAY INVISIBLE (-3025 4900);
FORCEPROP 1 LAST HDL_TAP TRUE
J 0
(-2700 4725);
DISPLAY 0.872340 (-2700 4725);
DISPLAY INVISIBLE (-2700 4725);
FORCEPROP 1 LAST PATH I707
J 0
(-3027 4850);
DISPLAY 0.872340 (-3027 4850);
PAINT GREEN (-3027 4850);
DISPLAY INVISIBLE (-3027 4850);
FORCEADD TAP..1
(-3025 4650);
FORCEPROP 3 LASTPIN (-3075 4650) SIG_NAME M_A_CPU0_SA_DQ<26>
J 0
(-3065 4660);
DISPLAY 0.659574 (-3065 4660);
PAINT MONO (-3065 4660);
DISPLAY INVISIBLE (-3065 4660);
FORCEPROP 1 LASTPIN (-3075 4650) BN 26
J 0
(-3087 4658);
DISPLAY 0.489362 (-3087 4658);
PAINT MONO (-3087 4658);
FORCEPROP 2 LAST CDS_LIB mstr_standard
J 0
(-3025 4650);
DISPLAY INVISIBLE (-3025 4650);
FORCEPROP 1 LAST BODY_TYPE PLUMBING
J 0
(-3025 4700);
DISPLAY 0.872340 (-3025 4700);
PAINT GREEN (-3025 4700);
DISPLAY INVISIBLE (-3025 4700);
FORCEPROP 1 LAST HDL_TAP TRUE
J 0
(-2700 4525);
DISPLAY 0.872340 (-2700 4525);
DISPLAY INVISIBLE (-2700 4525);
FORCEPROP 1 LAST PATH I708
J 0
(-3027 4650);
DISPLAY 0.872340 (-3027 4650);
PAINT GREEN (-3027 4650);
DISPLAY INVISIBLE (-3027 4650);
FORCEADD TAP..1
(-3025 4700);
FORCEPROP 3 LASTPIN (-3075 4700) SIG_NAME M_A_CPU0_SA_DQ<25>
J 0
(-3065 4710);
DISPLAY 0.659574 (-3065 4710);
PAINT MONO (-3065 4710);
DISPLAY INVISIBLE (-3065 4710);
FORCEPROP 1 LASTPIN (-3075 4700) BN 25
J 0
(-3087 4708);
DISPLAY 0.489362 (-3087 4708);
PAINT MONO (-3087 4708);
FORCEPROP 2 LAST CDS_LIB mstr_standard
J 0
(-3025 4700);
DISPLAY INVISIBLE (-3025 4700);
FORCEPROP 1 LAST BODY_TYPE PLUMBING
J 0
(-3025 4750);
DISPLAY 0.872340 (-3025 4750);
PAINT GREEN (-3025 4750);
DISPLAY INVISIBLE (-3025 4750);
FORCEPROP 1 LAST HDL_TAP TRUE
J 0
(-2700 4575);
DISPLAY 0.872340 (-2700 4575);
DISPLAY INVISIBLE (-2700 4575);
FORCEPROP 1 LAST PATH I709
J 0
(-3027 4700);
DISPLAY 0.872340 (-3027 4700);
PAINT GREEN (-3027 4700);
DISPLAY INVISIBLE (-3027 4700);
FORCEADD TAP..1
(-3025 4750);
FORCEPROP 3 LASTPIN (-3075 4750) SIG_NAME M_A_CPU0_SA_DQ<24>
J 0
(-3065 4760);
DISPLAY 0.659574 (-3065 4760);
PAINT MONO (-3065 4760);
DISPLAY INVISIBLE (-3065 4760);
FORCEPROP 1 LASTPIN (-3075 4750) BN 24
J 0
(-3087 4758);
DISPLAY 0.489362 (-3087 4758);
PAINT MONO (-3087 4758);
FORCEPROP 2 LAST CDS_LIB mstr_standard
J 0
(-3025 4750);
DISPLAY INVISIBLE (-3025 4750);
FORCEPROP 1 LAST BODY_TYPE PLUMBING
J 0
(-3025 4800);
DISPLAY 0.872340 (-3025 4800);
PAINT GREEN (-3025 4800);
DISPLAY INVISIBLE (-3025 4800);
FORCEPROP 1 LAST HDL_TAP TRUE
J 0
(-2700 4625);
DISPLAY 0.872340 (-2700 4625);
DISPLAY INVISIBLE (-2700 4625);
FORCEPROP 1 LAST PATH I710
J 0
(-3027 4750);
DISPLAY 0.872340 (-3027 4750);
PAINT GREEN (-3027 4750);
DISPLAY INVISIBLE (-3027 4750);
FORCEADD TAP..1
(-3025 4550);
FORCEPROP 3 LASTPIN (-3075 4550) SIG_NAME M_A_CPU0_SA_DQ<28>
J 0
(-3065 4560);
DISPLAY 0.659574 (-3065 4560);
PAINT MONO (-3065 4560);
DISPLAY INVISIBLE (-3065 4560);
FORCEPROP 1 LASTPIN (-3075 4550) BN 28
J 0
(-3087 4558);
DISPLAY 0.489362 (-3087 4558);
PAINT MONO (-3087 4558);
FORCEPROP 2 LAST CDS_LIB mstr_standard
J 0
(-3025 4550);
DISPLAY INVISIBLE (-3025 4550);
FORCEPROP 1 LAST BODY_TYPE PLUMBING
J 0
(-3025 4600);
DISPLAY 0.872340 (-3025 4600);
PAINT GREEN (-3025 4600);
DISPLAY INVISIBLE (-3025 4600);
FORCEPROP 1 LAST HDL_TAP TRUE
J 0
(-2700 4425);
DISPLAY 0.872340 (-2700 4425);
DISPLAY INVISIBLE (-2700 4425);
FORCEPROP 1 LAST PATH I711
J 0
(-3027 4550);
DISPLAY 0.872340 (-3027 4550);
PAINT GREEN (-3027 4550);
DISPLAY INVISIBLE (-3027 4550);
FORCEADD TAP..1
(-3025 4600);
FORCEPROP 3 LASTPIN (-3075 4600) SIG_NAME M_A_CPU0_SA_DQ<27>
J 0
(-3065 4610);
DISPLAY 0.659574 (-3065 4610);
PAINT MONO (-3065 4610);
DISPLAY INVISIBLE (-3065 4610);
FORCEPROP 1 LASTPIN (-3075 4600) BN 27
J 0
(-3087 4608);
DISPLAY 0.489362 (-3087 4608);
PAINT MONO (-3087 4608);
FORCEPROP 2 LAST CDS_LIB mstr_standard
J 0
(-3025 4600);
DISPLAY INVISIBLE (-3025 4600);
FORCEPROP 1 LAST BODY_TYPE PLUMBING
J 0
(-3025 4650);
DISPLAY 0.872340 (-3025 4650);
PAINT GREEN (-3025 4650);
DISPLAY INVISIBLE (-3025 4650);
FORCEPROP 1 LAST HDL_TAP TRUE
J 0
(-2700 4475);
DISPLAY 0.872340 (-2700 4475);
DISPLAY INVISIBLE (-2700 4475);
FORCEPROP 1 LAST PATH I712
J 0
(-3027 4600);
DISPLAY 0.872340 (-3027 4600);
PAINT GREEN (-3027 4600);
DISPLAY INVISIBLE (-3027 4600);
FORCEADD TAP..1
(-3025 4400);
FORCEPROP 3 LASTPIN (-3075 4400) SIG_NAME M_A_CPU0_SA_DQ<31>
J 0
(-3065 4410);
DISPLAY 0.659574 (-3065 4410);
PAINT MONO (-3065 4410);
DISPLAY INVISIBLE (-3065 4410);
FORCEPROP 1 LASTPIN (-3075 4400) BN 31
J 0
(-3087 4408);
DISPLAY 0.489362 (-3087 4408);
PAINT MONO (-3087 4408);
FORCEPROP 2 LAST CDS_LIB mstr_standard
J 0
(-3025 4400);
DISPLAY INVISIBLE (-3025 4400);
FORCEPROP 1 LAST BODY_TYPE PLUMBING
J 0
(-3025 4450);
DISPLAY 0.872340 (-3025 4450);
PAINT GREEN (-3025 4450);
DISPLAY INVISIBLE (-3025 4450);
FORCEPROP 1 LAST HDL_TAP TRUE
J 0
(-2700 4275);
DISPLAY 0.872340 (-2700 4275);
DISPLAY INVISIBLE (-2700 4275);
FORCEPROP 1 LAST PATH I713
J 0
(-3027 4400);
DISPLAY 0.872340 (-3027 4400);
PAINT GREEN (-3027 4400);
DISPLAY INVISIBLE (-3027 4400);
FORCEADD TAP..1
(-3025 4450);
FORCEPROP 3 LASTPIN (-3075 4450) SIG_NAME M_A_CPU0_SA_DQ<30>
J 0
(-3065 4460);
DISPLAY 0.659574 (-3065 4460);
PAINT MONO (-3065 4460);
DISPLAY INVISIBLE (-3065 4460);
FORCEPROP 1 LASTPIN (-3075 4450) BN 30
J 0
(-3087 4458);
DISPLAY 0.489362 (-3087 4458);
PAINT MONO (-3087 4458);
FORCEPROP 2 LAST CDS_LIB mstr_standard
J 0
(-3025 4450);
DISPLAY INVISIBLE (-3025 4450);
FORCEPROP 1 LAST BODY_TYPE PLUMBING
J 0
(-3025 4500);
DISPLAY 0.872340 (-3025 4500);
PAINT GREEN (-3025 4500);
DISPLAY INVISIBLE (-3025 4500);
FORCEPROP 1 LAST HDL_TAP TRUE
J 0
(-2700 4325);
DISPLAY 0.872340 (-2700 4325);
DISPLAY INVISIBLE (-2700 4325);
FORCEPROP 1 LAST PATH I714
J 0
(-3027 4450);
DISPLAY 0.872340 (-3027 4450);
PAINT GREEN (-3027 4450);
DISPLAY INVISIBLE (-3027 4450);
FORCEADD TAP..1
(-3025 4500);
FORCEPROP 3 LASTPIN (-3075 4500) SIG_NAME M_A_CPU0_SA_DQ<29>
J 0
(-3065 4510);
DISPLAY 0.659574 (-3065 4510);
PAINT MONO (-3065 4510);
DISPLAY INVISIBLE (-3065 4510);
FORCEPROP 1 LASTPIN (-3075 4500) BN 29
J 0
(-3087 4508);
DISPLAY 0.489362 (-3087 4508);
PAINT MONO (-3087 4508);
FORCEPROP 2 LAST CDS_LIB mstr_standard
J 0
(-3025 4500);
DISPLAY INVISIBLE (-3025 4500);
FORCEPROP 1 LAST BODY_TYPE PLUMBING
J 0
(-3025 4550);
DISPLAY 0.872340 (-3025 4550);
PAINT GREEN (-3025 4550);
DISPLAY INVISIBLE (-3025 4550);
FORCEPROP 1 LAST HDL_TAP TRUE
J 0
(-2700 4375);
DISPLAY 0.872340 (-2700 4375);
DISPLAY INVISIBLE (-2700 4375);
FORCEPROP 1 LAST PATH I715
J 0
(-3027 4500);
DISPLAY 0.872340 (-3027 4500);
PAINT GREEN (-3027 4500);
DISPLAY INVISIBLE (-3027 4500);
FORCEADD TAP..1
(-3025 4300);
FORCEPROP 3 LASTPIN (-3075 4300) SIG_NAME M_A_CPU0_SB_DQ<0>
J 0
(-3065 4310);
DISPLAY 0.659574 (-3065 4310);
PAINT MONO (-3065 4310);
DISPLAY INVISIBLE (-3065 4310);
FORCEPROP 1 LASTPIN (-3075 4300) BN 0
J 0
(-3087 4308);
DISPLAY 0.489362 (-3087 4308);
PAINT MONO (-3087 4308);
FORCEPROP 2 LAST CDS_LIB mstr_standard
J 0
(-3025 4300);
DISPLAY INVISIBLE (-3025 4300);
FORCEPROP 1 LAST BODY_TYPE PLUMBING
J 0
(-3025 4350);
DISPLAY 0.872340 (-3025 4350);
PAINT GREEN (-3025 4350);
DISPLAY INVISIBLE (-3025 4350);
FORCEPROP 1 LAST HDL_TAP TRUE
J 0
(-2700 4175);
DISPLAY 0.872340 (-2700 4175);
DISPLAY INVISIBLE (-2700 4175);
FORCEPROP 1 LAST PATH I716
J 0
(-3027 4300);
DISPLAY 0.872340 (-3027 4300);
PAINT GREEN (-3027 4300);
DISPLAY INVISIBLE (-3027 4300);
FORCEADD TAP..1
(-3025 4150);
FORCEPROP 3 LASTPIN (-3075 4150) SIG_NAME M_A_CPU0_SB_DQ<3>
J 0
(-3065 4160);
DISPLAY 0.659574 (-3065 4160);
PAINT MONO (-3065 4160);
DISPLAY INVISIBLE (-3065 4160);
FORCEPROP 1 LASTPIN (-3075 4150) BN 3
J 0
(-3087 4158);
DISPLAY 0.489362 (-3087 4158);
PAINT MONO (-3087 4158);
FORCEPROP 2 LAST CDS_LIB mstr_standard
J 0
(-3025 4150);
DISPLAY INVISIBLE (-3025 4150);
FORCEPROP 1 LAST BODY_TYPE PLUMBING
J 0
(-3025 4200);
DISPLAY 0.872340 (-3025 4200);
PAINT GREEN (-3025 4200);
DISPLAY INVISIBLE (-3025 4200);
FORCEPROP 1 LAST HDL_TAP TRUE
J 0
(-2700 4025);
DISPLAY 0.872340 (-2700 4025);
DISPLAY INVISIBLE (-2700 4025);
FORCEPROP 1 LAST PATH I717
J 0
(-3027 4150);
DISPLAY 0.872340 (-3027 4150);
PAINT GREEN (-3027 4150);
DISPLAY INVISIBLE (-3027 4150);
FORCEADD TAP..1
(-3025 4200);
FORCEPROP 3 LASTPIN (-3075 4200) SIG_NAME M_A_CPU0_SB_DQ<2>
J 0
(-3065 4210);
DISPLAY 0.659574 (-3065 4210);
PAINT MONO (-3065 4210);
DISPLAY INVISIBLE (-3065 4210);
FORCEPROP 1 LASTPIN (-3075 4200) BN 2
J 0
(-3087 4208);
DISPLAY 0.489362 (-3087 4208);
PAINT MONO (-3087 4208);
FORCEPROP 2 LAST CDS_LIB mstr_standard
J 0
(-3025 4200);
DISPLAY INVISIBLE (-3025 4200);
FORCEPROP 1 LAST BODY_TYPE PLUMBING
J 0
(-3025 4250);
DISPLAY 0.872340 (-3025 4250);
PAINT GREEN (-3025 4250);
DISPLAY INVISIBLE (-3025 4250);
FORCEPROP 1 LAST HDL_TAP TRUE
J 0
(-2700 4075);
DISPLAY 0.872340 (-2700 4075);
DISPLAY INVISIBLE (-2700 4075);
FORCEPROP 1 LAST PATH I718
J 0
(-3027 4200);
DISPLAY 0.872340 (-3027 4200);
PAINT GREEN (-3027 4200);
DISPLAY INVISIBLE (-3027 4200);
FORCEADD TAP..1
(-3025 4250);
FORCEPROP 3 LASTPIN (-3075 4250) SIG_NAME M_A_CPU0_SB_DQ<1>
J 0
(-3065 4260);
DISPLAY 0.659574 (-3065 4260);
PAINT MONO (-3065 4260);
DISPLAY INVISIBLE (-3065 4260);
FORCEPROP 1 LASTPIN (-3075 4250) BN 1
J 0
(-3087 4258);
DISPLAY 0.489362 (-3087 4258);
PAINT MONO (-3087 4258);
FORCEPROP 2 LAST CDS_LIB mstr_standard
J 0
(-3025 4250);
DISPLAY INVISIBLE (-3025 4250);
FORCEPROP 1 LAST BODY_TYPE PLUMBING
J 0
(-3025 4300);
DISPLAY 0.872340 (-3025 4300);
PAINT GREEN (-3025 4300);
DISPLAY INVISIBLE (-3025 4300);
FORCEPROP 1 LAST HDL_TAP TRUE
J 0
(-2700 4125);
DISPLAY 0.872340 (-2700 4125);
DISPLAY INVISIBLE (-2700 4125);
FORCEPROP 1 LAST PATH I719
J 0
(-3027 4250);
DISPLAY 0.872340 (-3027 4250);
PAINT GREEN (-3027 4250);
DISPLAY INVISIBLE (-3027 4250);
FORCEADD TAP..1
(-3025 4100);
FORCEPROP 3 LASTPIN (-3075 4100) SIG_NAME M_A_CPU0_SB_DQ<4>
J 0
(-3065 4110);
DISPLAY 0.659574 (-3065 4110);
PAINT MONO (-3065 4110);
DISPLAY INVISIBLE (-3065 4110);
FORCEPROP 1 LASTPIN (-3075 4100) BN 4
J 0
(-3087 4108);
DISPLAY 0.489362 (-3087 4108);
PAINT MONO (-3087 4108);
FORCEPROP 2 LAST CDS_LIB mstr_standard
J 0
(-3025 4100);
DISPLAY INVISIBLE (-3025 4100);
FORCEPROP 1 LAST BODY_TYPE PLUMBING
J 0
(-3025 4150);
DISPLAY 0.872340 (-3025 4150);
PAINT GREEN (-3025 4150);
DISPLAY INVISIBLE (-3025 4150);
FORCEPROP 1 LAST HDL_TAP TRUE
J 0
(-2700 3975);
DISPLAY 0.872340 (-2700 3975);
DISPLAY INVISIBLE (-2700 3975);
FORCEPROP 1 LAST PATH I720
J 0
(-3027 4100);
DISPLAY 0.872340 (-3027 4100);
PAINT GREEN (-3027 4100);
DISPLAY INVISIBLE (-3027 4100);
FORCEADD TAP..1
(-3025 4050);
FORCEPROP 3 LASTPIN (-3075 4050) SIG_NAME M_A_CPU0_SB_DQ<5>
J 0
(-3065 4060);
DISPLAY 0.659574 (-3065 4060);
PAINT MONO (-3065 4060);
DISPLAY INVISIBLE (-3065 4060);
FORCEPROP 1 LASTPIN (-3075 4050) BN 5
J 0
(-3087 4058);
DISPLAY 0.489362 (-3087 4058);
PAINT MONO (-3087 4058);
FORCEPROP 2 LAST CDS_LIB mstr_standard
J 0
(-3025 4050);
DISPLAY INVISIBLE (-3025 4050);
FORCEPROP 1 LAST BODY_TYPE PLUMBING
J 0
(-3025 4100);
DISPLAY 0.872340 (-3025 4100);
PAINT GREEN (-3025 4100);
DISPLAY INVISIBLE (-3025 4100);
FORCEPROP 1 LAST HDL_TAP TRUE
J 0
(-2700 3925);
DISPLAY 0.872340 (-2700 3925);
DISPLAY INVISIBLE (-2700 3925);
FORCEPROP 1 LAST PATH I721
J 0
(-3027 4050);
DISPLAY 0.872340 (-3027 4050);
PAINT GREEN (-3027 4050);
DISPLAY INVISIBLE (-3027 4050);
FORCEADD TAP..1
(-3025 3850);
FORCEPROP 3 LASTPIN (-3075 3850) SIG_NAME M_A_CPU0_SB_DQ<8>
J 0
(-3065 3860);
DISPLAY 0.659574 (-3065 3860);
PAINT MONO (-3065 3860);
DISPLAY INVISIBLE (-3065 3860);
FORCEPROP 1 LASTPIN (-3075 3850) BN 8
J 0
(-3087 3858);
DISPLAY 0.489362 (-3087 3858);
PAINT MONO (-3087 3858);
FORCEPROP 2 LAST CDS_LIB mstr_standard
J 0
(-3025 3850);
DISPLAY INVISIBLE (-3025 3850);
FORCEPROP 1 LAST BODY_TYPE PLUMBING
J 0
(-3025 3900);
DISPLAY 0.872340 (-3025 3900);
PAINT GREEN (-3025 3900);
DISPLAY INVISIBLE (-3025 3900);
FORCEPROP 1 LAST HDL_TAP TRUE
J 0
(-2700 3725);
DISPLAY 0.872340 (-2700 3725);
DISPLAY INVISIBLE (-2700 3725);
FORCEPROP 1 LAST PATH I722
J 0
(-3027 3850);
DISPLAY 0.872340 (-3027 3850);
PAINT GREEN (-3027 3850);
DISPLAY INVISIBLE (-3027 3850);
FORCEADD TAP..1
(-3025 3950);
FORCEPROP 3 LASTPIN (-3075 3950) SIG_NAME M_A_CPU0_SB_DQ<7>
J 0
(-3065 3960);
DISPLAY 0.659574 (-3065 3960);
PAINT MONO (-3065 3960);
DISPLAY INVISIBLE (-3065 3960);
FORCEPROP 1 LASTPIN (-3075 3950) BN 7
J 0
(-3087 3958);
DISPLAY 0.489362 (-3087 3958);
PAINT MONO (-3087 3958);
FORCEPROP 2 LAST CDS_LIB mstr_standard
J 0
(-3025 3950);
DISPLAY INVISIBLE (-3025 3950);
FORCEPROP 1 LAST BODY_TYPE PLUMBING
J 0
(-3025 4000);
DISPLAY 0.872340 (-3025 4000);
PAINT GREEN (-3025 4000);
DISPLAY INVISIBLE (-3025 4000);
FORCEPROP 1 LAST HDL_TAP TRUE
J 0
(-2700 3825);
DISPLAY 0.872340 (-2700 3825);
DISPLAY INVISIBLE (-2700 3825);
FORCEPROP 1 LAST PATH I723
J 0
(-3027 3950);
DISPLAY 0.872340 (-3027 3950);
PAINT GREEN (-3027 3950);
DISPLAY INVISIBLE (-3027 3950);
FORCEADD TAP..1
(-3025 4000);
FORCEPROP 3 LASTPIN (-3075 4000) SIG_NAME M_A_CPU0_SB_DQ<6>
J 0
(-3065 4010);
DISPLAY 0.659574 (-3065 4010);
PAINT MONO (-3065 4010);
DISPLAY INVISIBLE (-3065 4010);
FORCEPROP 1 LASTPIN (-3075 4000) BN 6
J 0
(-3087 4008);
DISPLAY 0.489362 (-3087 4008);
PAINT MONO (-3087 4008);
FORCEPROP 2 LAST CDS_LIB mstr_standard
J 0
(-3025 4000);
DISPLAY INVISIBLE (-3025 4000);
FORCEPROP 1 LAST BODY_TYPE PLUMBING
J 0
(-3025 4050);
DISPLAY 0.872340 (-3025 4050);
PAINT GREEN (-3025 4050);
DISPLAY INVISIBLE (-3025 4050);
FORCEPROP 1 LAST HDL_TAP TRUE
J 0
(-2700 3875);
DISPLAY 0.872340 (-2700 3875);
DISPLAY INVISIBLE (-2700 3875);
FORCEPROP 1 LAST PATH I724
J 0
(-3027 4000);
DISPLAY 0.872340 (-3027 4000);
PAINT GREEN (-3027 4000);
DISPLAY INVISIBLE (-3027 4000);
FORCEADD TAP..1
(-3025 3800);
FORCEPROP 3 LASTPIN (-3075 3800) SIG_NAME M_A_CPU0_SB_DQ<9>
J 0
(-3065 3810);
DISPLAY 0.659574 (-3065 3810);
PAINT MONO (-3065 3810);
DISPLAY INVISIBLE (-3065 3810);
FORCEPROP 1 LASTPIN (-3075 3800) BN 9
J 0
(-3087 3808);
DISPLAY 0.489362 (-3087 3808);
PAINT MONO (-3087 3808);
FORCEPROP 2 LAST CDS_LIB mstr_standard
J 0
(-3025 3800);
DISPLAY INVISIBLE (-3025 3800);
FORCEPROP 1 LAST BODY_TYPE PLUMBING
J 0
(-3025 3850);
DISPLAY 0.872340 (-3025 3850);
PAINT GREEN (-3025 3850);
DISPLAY INVISIBLE (-3025 3850);
FORCEPROP 1 LAST HDL_TAP TRUE
J 0
(-2700 3675);
DISPLAY 0.872340 (-2700 3675);
DISPLAY INVISIBLE (-2700 3675);
FORCEPROP 1 LAST PATH I725
J 0
(-3027 3800);
DISPLAY 0.872340 (-3027 3800);
PAINT GREEN (-3027 3800);
DISPLAY INVISIBLE (-3027 3800);
FORCEADD TAP..1
(-3025 3600);
FORCEPROP 3 LASTPIN (-3075 3600) SIG_NAME M_A_CPU0_SB_DQ<13>
J 0
(-3065 3610);
DISPLAY 0.659574 (-3065 3610);
PAINT MONO (-3065 3610);
DISPLAY INVISIBLE (-3065 3610);
FORCEPROP 1 LASTPIN (-3075 3600) BN 13
J 0
(-3087 3608);
DISPLAY 0.489362 (-3087 3608);
PAINT MONO (-3087 3608);
FORCEPROP 2 LAST CDS_LIB mstr_standard
J 0
(-3025 3600);
DISPLAY INVISIBLE (-3025 3600);
FORCEPROP 1 LAST BODY_TYPE PLUMBING
J 0
(-3025 3650);
DISPLAY 0.872340 (-3025 3650);
PAINT GREEN (-3025 3650);
DISPLAY INVISIBLE (-3025 3650);
FORCEPROP 1 LAST HDL_TAP TRUE
J 0
(-2700 3475);
DISPLAY 0.872340 (-2700 3475);
DISPLAY INVISIBLE (-2700 3475);
FORCEPROP 1 LAST PATH I726
J 0
(-3027 3600);
DISPLAY 0.872340 (-3027 3600);
PAINT GREEN (-3027 3600);
DISPLAY INVISIBLE (-3027 3600);
FORCEADD TAP..1
(-3025 3700);
FORCEPROP 3 LASTPIN (-3075 3700) SIG_NAME M_A_CPU0_SB_DQ<11>
J 0
(-3065 3710);
DISPLAY 0.659574 (-3065 3710);
PAINT MONO (-3065 3710);
DISPLAY INVISIBLE (-3065 3710);
FORCEPROP 1 LASTPIN (-3075 3700) BN 11
J 0
(-3087 3708);
DISPLAY 0.489362 (-3087 3708);
PAINT MONO (-3087 3708);
FORCEPROP 2 LAST CDS_LIB mstr_standard
J 0
(-3025 3700);
DISPLAY INVISIBLE (-3025 3700);
FORCEPROP 1 LAST BODY_TYPE PLUMBING
J 0
(-3025 3750);
DISPLAY 0.872340 (-3025 3750);
PAINT GREEN (-3025 3750);
DISPLAY INVISIBLE (-3025 3750);
FORCEPROP 1 LAST HDL_TAP TRUE
J 0
(-2700 3575);
DISPLAY 0.872340 (-2700 3575);
DISPLAY INVISIBLE (-2700 3575);
FORCEPROP 1 LAST PATH I727
J 0
(-3027 3700);
DISPLAY 0.872340 (-3027 3700);
PAINT GREEN (-3027 3700);
DISPLAY INVISIBLE (-3027 3700);
FORCEADD TAP..1
(-3025 3650);
FORCEPROP 3 LASTPIN (-3075 3650) SIG_NAME M_A_CPU0_SB_DQ<12>
J 0
(-3065 3660);
DISPLAY 0.659574 (-3065 3660);
PAINT MONO (-3065 3660);
DISPLAY INVISIBLE (-3065 3660);
FORCEPROP 1 LASTPIN (-3075 3650) BN 12
J 0
(-3087 3658);
DISPLAY 0.489362 (-3087 3658);
PAINT MONO (-3087 3658);
FORCEPROP 2 LAST CDS_LIB mstr_standard
J 0
(-3025 3650);
DISPLAY INVISIBLE (-3025 3650);
FORCEPROP 1 LAST BODY_TYPE PLUMBING
J 0
(-3025 3700);
DISPLAY 0.872340 (-3025 3700);
PAINT GREEN (-3025 3700);
DISPLAY INVISIBLE (-3025 3700);
FORCEPROP 1 LAST HDL_TAP TRUE
J 0
(-2700 3525);
DISPLAY 0.872340 (-2700 3525);
DISPLAY INVISIBLE (-2700 3525);
FORCEPROP 1 LAST PATH I728
J 0
(-3027 3650);
DISPLAY 0.872340 (-3027 3650);
PAINT GREEN (-3027 3650);
DISPLAY INVISIBLE (-3027 3650);
FORCEADD TAP..1
(-3025 3750);
FORCEPROP 3 LASTPIN (-3075 3750) SIG_NAME M_A_CPU0_SB_DQ<10>
J 0
(-3065 3760);
DISPLAY 0.659574 (-3065 3760);
PAINT MONO (-3065 3760);
DISPLAY INVISIBLE (-3065 3760);
FORCEPROP 1 LASTPIN (-3075 3750) BN 10
J 0
(-3087 3758);
DISPLAY 0.489362 (-3087 3758);
PAINT MONO (-3087 3758);
FORCEPROP 2 LAST CDS_LIB mstr_standard
J 0
(-3025 3750);
DISPLAY INVISIBLE (-3025 3750);
FORCEPROP 1 LAST BODY_TYPE PLUMBING
J 0
(-3025 3800);
DISPLAY 0.872340 (-3025 3800);
PAINT GREEN (-3025 3800);
DISPLAY INVISIBLE (-3025 3800);
FORCEPROP 1 LAST HDL_TAP TRUE
J 0
(-2700 3625);
DISPLAY 0.872340 (-2700 3625);
DISPLAY INVISIBLE (-2700 3625);
FORCEPROP 1 LAST PATH I729
J 0
(-3027 3750);
DISPLAY 0.872340 (-3027 3750);
PAINT GREEN (-3027 3750);
DISPLAY INVISIBLE (-3027 3750);
FORCEADD TAP..1
(-3025 3550);
FORCEPROP 3 LASTPIN (-3075 3550) SIG_NAME M_A_CPU0_SB_DQ<14>
J 0
(-3065 3560);
DISPLAY 0.659574 (-3065 3560);
PAINT MONO (-3065 3560);
DISPLAY INVISIBLE (-3065 3560);
FORCEPROP 1 LASTPIN (-3075 3550) BN 14
J 0
(-3087 3558);
DISPLAY 0.489362 (-3087 3558);
PAINT MONO (-3087 3558);
FORCEPROP 2 LAST CDS_LIB mstr_standard
J 0
(-3025 3550);
DISPLAY INVISIBLE (-3025 3550);
FORCEPROP 1 LAST BODY_TYPE PLUMBING
J 0
(-3025 3600);
DISPLAY 0.872340 (-3025 3600);
PAINT GREEN (-3025 3600);
DISPLAY INVISIBLE (-3025 3600);
FORCEPROP 1 LAST HDL_TAP TRUE
J 0
(-2700 3425);
DISPLAY 0.872340 (-2700 3425);
DISPLAY INVISIBLE (-2700 3425);
FORCEPROP 1 LAST PATH I730
J 0
(-3027 3550);
DISPLAY 0.872340 (-3027 3550);
PAINT GREEN (-3027 3550);
DISPLAY INVISIBLE (-3027 3550);
FORCEADD TAP..1
(-3025 3400);
FORCEPROP 3 LASTPIN (-3075 3400) SIG_NAME M_A_CPU0_SB_DQ<16>
J 0
(-3065 3410);
DISPLAY 0.659574 (-3065 3410);
PAINT MONO (-3065 3410);
DISPLAY INVISIBLE (-3065 3410);
FORCEPROP 1 LASTPIN (-3075 3400) BN 16
J 0
(-3087 3408);
DISPLAY 0.489362 (-3087 3408);
PAINT MONO (-3087 3408);
FORCEPROP 2 LAST CDS_LIB mstr_standard
J 0
(-3025 3400);
DISPLAY INVISIBLE (-3025 3400);
FORCEPROP 1 LAST BODY_TYPE PLUMBING
J 0
(-3025 3450);
DISPLAY 0.872340 (-3025 3450);
PAINT GREEN (-3025 3450);
DISPLAY INVISIBLE (-3025 3450);
FORCEPROP 1 LAST HDL_TAP TRUE
J 0
(-2700 3275);
DISPLAY 0.872340 (-2700 3275);
DISPLAY INVISIBLE (-2700 3275);
FORCEPROP 1 LAST PATH I731
J 0
(-3027 3400);
DISPLAY 0.872340 (-3027 3400);
PAINT GREEN (-3027 3400);
DISPLAY INVISIBLE (-3027 3400);
FORCEADD TAP..1
(-3025 3350);
FORCEPROP 3 LASTPIN (-3075 3350) SIG_NAME M_A_CPU0_SB_DQ<17>
J 0
(-3065 3360);
DISPLAY 0.659574 (-3065 3360);
PAINT MONO (-3065 3360);
DISPLAY INVISIBLE (-3065 3360);
FORCEPROP 1 LASTPIN (-3075 3350) BN 17
J 0
(-3087 3358);
DISPLAY 0.489362 (-3087 3358);
PAINT MONO (-3087 3358);
FORCEPROP 2 LAST CDS_LIB mstr_standard
J 0
(-3025 3350);
DISPLAY INVISIBLE (-3025 3350);
FORCEPROP 1 LAST BODY_TYPE PLUMBING
J 0
(-3025 3400);
DISPLAY 0.872340 (-3025 3400);
PAINT GREEN (-3025 3400);
DISPLAY INVISIBLE (-3025 3400);
FORCEPROP 1 LAST HDL_TAP TRUE
J 0
(-2700 3225);
DISPLAY 0.872340 (-2700 3225);
DISPLAY INVISIBLE (-2700 3225);
FORCEPROP 1 LAST PATH I732
J 0
(-3027 3350);
DISPLAY 0.872340 (-3027 3350);
PAINT GREEN (-3027 3350);
DISPLAY INVISIBLE (-3027 3350);
FORCEADD TAP..1
(-3025 3500);
FORCEPROP 3 LASTPIN (-3075 3500) SIG_NAME M_A_CPU0_SB_DQ<15>
J 0
(-3065 3510);
DISPLAY 0.659574 (-3065 3510);
PAINT MONO (-3065 3510);
DISPLAY INVISIBLE (-3065 3510);
FORCEPROP 1 LASTPIN (-3075 3500) BN 15
J 0
(-3087 3508);
DISPLAY 0.489362 (-3087 3508);
PAINT MONO (-3087 3508);
FORCEPROP 2 LAST CDS_LIB mstr_standard
J 0
(-3025 3500);
DISPLAY INVISIBLE (-3025 3500);
FORCEPROP 1 LAST BODY_TYPE PLUMBING
J 0
(-3025 3550);
DISPLAY 0.872340 (-3025 3550);
PAINT GREEN (-3025 3550);
DISPLAY INVISIBLE (-3025 3550);
FORCEPROP 1 LAST HDL_TAP TRUE
J 0
(-2700 3375);
DISPLAY 0.872340 (-2700 3375);
DISPLAY INVISIBLE (-2700 3375);
FORCEPROP 1 LAST PATH I733
J 0
(-3027 3500);
DISPLAY 0.872340 (-3027 3500);
PAINT GREEN (-3027 3500);
DISPLAY INVISIBLE (-3027 3500);
FORCEADD TAP..1
(-3025 3300);
FORCEPROP 3 LASTPIN (-3075 3300) SIG_NAME M_A_CPU0_SB_DQ<18>
J 0
(-3065 3310);
DISPLAY 0.659574 (-3065 3310);
PAINT MONO (-3065 3310);
DISPLAY INVISIBLE (-3065 3310);
FORCEPROP 1 LASTPIN (-3075 3300) BN 18
J 0
(-3087 3308);
DISPLAY 0.489362 (-3087 3308);
PAINT MONO (-3087 3308);
FORCEPROP 2 LAST CDS_LIB mstr_standard
J 0
(-3025 3300);
DISPLAY INVISIBLE (-3025 3300);
FORCEPROP 1 LAST BODY_TYPE PLUMBING
J 0
(-3025 3350);
DISPLAY 0.872340 (-3025 3350);
PAINT GREEN (-3025 3350);
DISPLAY INVISIBLE (-3025 3350);
FORCEPROP 1 LAST HDL_TAP TRUE
J 0
(-2700 3175);
DISPLAY 0.872340 (-2700 3175);
DISPLAY INVISIBLE (-2700 3175);
FORCEPROP 1 LAST PATH I734
J 0
(-3027 3300);
DISPLAY 0.872340 (-3027 3300);
PAINT GREEN (-3027 3300);
DISPLAY INVISIBLE (-3027 3300);
FORCEADD TAP..1
(-3025 3100);
FORCEPROP 3 LASTPIN (-3075 3100) SIG_NAME M_A_CPU0_SB_DQ<22>
J 0
(-3065 3110);
DISPLAY 0.659574 (-3065 3110);
PAINT MONO (-3065 3110);
DISPLAY INVISIBLE (-3065 3110);
FORCEPROP 1 LASTPIN (-3075 3100) BN 22
J 0
(-3087 3108);
DISPLAY 0.489362 (-3087 3108);
PAINT MONO (-3087 3108);
FORCEPROP 2 LAST CDS_LIB mstr_standard
J 0
(-3025 3100);
DISPLAY INVISIBLE (-3025 3100);
FORCEPROP 1 LAST BODY_TYPE PLUMBING
J 0
(-3025 3150);
DISPLAY 0.872340 (-3025 3150);
PAINT GREEN (-3025 3150);
DISPLAY INVISIBLE (-3025 3150);
FORCEPROP 1 LAST HDL_TAP TRUE
J 0
(-2700 2975);
DISPLAY 0.872340 (-2700 2975);
DISPLAY INVISIBLE (-2700 2975);
FORCEPROP 1 LAST PATH I735
J 0
(-3027 3100);
DISPLAY 0.872340 (-3027 3100);
PAINT GREEN (-3027 3100);
DISPLAY INVISIBLE (-3027 3100);
FORCEADD TAP..1
(-3025 3150);
FORCEPROP 3 LASTPIN (-3075 3150) SIG_NAME M_A_CPU0_SB_DQ<21>
J 0
(-3065 3160);
DISPLAY 0.659574 (-3065 3160);
PAINT MONO (-3065 3160);
DISPLAY INVISIBLE (-3065 3160);
FORCEPROP 1 LASTPIN (-3075 3150) BN 21
J 0
(-3087 3158);
DISPLAY 0.489362 (-3087 3158);
PAINT MONO (-3087 3158);
FORCEPROP 2 LAST CDS_LIB mstr_standard
J 0
(-3025 3150);
DISPLAY INVISIBLE (-3025 3150);
FORCEPROP 1 LAST BODY_TYPE PLUMBING
J 0
(-3025 3200);
DISPLAY 0.872340 (-3025 3200);
PAINT GREEN (-3025 3200);
DISPLAY INVISIBLE (-3025 3200);
FORCEPROP 1 LAST HDL_TAP TRUE
J 0
(-2700 3025);
DISPLAY 0.872340 (-2700 3025);
DISPLAY INVISIBLE (-2700 3025);
FORCEPROP 1 LAST PATH I736
J 0
(-3027 3150);
DISPLAY 0.872340 (-3027 3150);
PAINT GREEN (-3027 3150);
DISPLAY INVISIBLE (-3027 3150);
FORCEADD TAP..1
(-3025 3200);
FORCEPROP 3 LASTPIN (-3075 3200) SIG_NAME M_A_CPU0_SB_DQ<20>
J 0
(-3065 3210);
DISPLAY 0.659574 (-3065 3210);
PAINT MONO (-3065 3210);
DISPLAY INVISIBLE (-3065 3210);
FORCEPROP 1 LASTPIN (-3075 3200) BN 20
J 0
(-3087 3208);
DISPLAY 0.489362 (-3087 3208);
PAINT MONO (-3087 3208);
FORCEPROP 2 LAST CDS_LIB mstr_standard
J 0
(-3025 3200);
DISPLAY INVISIBLE (-3025 3200);
FORCEPROP 1 LAST BODY_TYPE PLUMBING
J 0
(-3025 3250);
DISPLAY 0.872340 (-3025 3250);
PAINT GREEN (-3025 3250);
DISPLAY INVISIBLE (-3025 3250);
FORCEPROP 1 LAST HDL_TAP TRUE
J 0
(-2700 3075);
DISPLAY 0.872340 (-2700 3075);
DISPLAY INVISIBLE (-2700 3075);
FORCEPROP 1 LAST PATH I737
J 0
(-3027 3200);
DISPLAY 0.872340 (-3027 3200);
PAINT GREEN (-3027 3200);
DISPLAY INVISIBLE (-3027 3200);
FORCEADD TAP..1
(-3025 3250);
FORCEPROP 3 LASTPIN (-3075 3250) SIG_NAME M_A_CPU0_SB_DQ<19>
J 0
(-3065 3260);
DISPLAY 0.659574 (-3065 3260);
PAINT MONO (-3065 3260);
DISPLAY INVISIBLE (-3065 3260);
FORCEPROP 1 LASTPIN (-3075 3250) BN 19
J 0
(-3087 3258);
DISPLAY 0.489362 (-3087 3258);
PAINT MONO (-3087 3258);
FORCEPROP 2 LAST CDS_LIB mstr_standard
J 0
(-3025 3250);
DISPLAY INVISIBLE (-3025 3250);
FORCEPROP 1 LAST BODY_TYPE PLUMBING
J 0
(-3025 3300);
DISPLAY 0.872340 (-3025 3300);
PAINT GREEN (-3025 3300);
DISPLAY INVISIBLE (-3025 3300);
FORCEPROP 1 LAST HDL_TAP TRUE
J 0
(-2700 3125);
DISPLAY 0.872340 (-2700 3125);
DISPLAY INVISIBLE (-2700 3125);
FORCEPROP 1 LAST PATH I738
J 0
(-3027 3250);
DISPLAY 0.872340 (-3027 3250);
PAINT GREEN (-3027 3250);
DISPLAY INVISIBLE (-3027 3250);
FORCEADD TAP..1
(-3025 3050);
FORCEPROP 3 LASTPIN (-3075 3050) SIG_NAME M_A_CPU0_SB_DQ<23>
J 0
(-3065 3060);
DISPLAY 0.659574 (-3065 3060);
PAINT MONO (-3065 3060);
DISPLAY INVISIBLE (-3065 3060);
FORCEPROP 1 LASTPIN (-3075 3050) BN 23
J 0
(-3087 3058);
DISPLAY 0.489362 (-3087 3058);
PAINT MONO (-3087 3058);
FORCEPROP 2 LAST CDS_LIB mstr_standard
J 0
(-3025 3050);
DISPLAY INVISIBLE (-3025 3050);
FORCEPROP 1 LAST BODY_TYPE PLUMBING
J 0
(-3025 3100);
DISPLAY 0.872340 (-3025 3100);
PAINT GREEN (-3025 3100);
DISPLAY INVISIBLE (-3025 3100);
FORCEPROP 1 LAST HDL_TAP TRUE
J 0
(-2700 2925);
DISPLAY 0.872340 (-2700 2925);
DISPLAY INVISIBLE (-2700 2925);
FORCEPROP 1 LAST PATH I739
J 0
(-3027 3050);
DISPLAY 0.872340 (-3027 3050);
PAINT GREEN (-3027 3050);
DISPLAY INVISIBLE (-3027 3050);
FORCEADD OFFPAGE..6
R 2
(-2425 2550);
FORCEPROP 2 LAST $XR0 85 
J 0
(-2211 2550);
DISPLAY 0.638298 (-2211 2550);
PAINT MONO (-2211 2550);
FORCEPROP 2 LAST PATH I740
J 0
(-2200 2600);
DISPLAY 1.021277 (-2200 2600);
DISPLAY INVISIBLE (-2200 2600);
FORCEPROP 1 LAST COMMENT_BODY TRUE
J 2
(-2525 2475);
DISPLAY 0.872340 (-2525 2475);
PAINT GREEN (-2525 2475);
DISPLAY INVISIBLE (-2525 2475);
FORCEPROP 1 LAST OFFPAGE TRUE
J 2
(-2750 2425);
DISPLAY 0.872340 (-2750 2425);
PAINT GREEN (-2750 2425);
DISPLAY INVISIBLE (-2750 2425);
FORCEPROP 2 LAST CDS_LIB mstr_standard
J 0
(-2425 2550);
DISPLAY INVISIBLE (-2425 2550);
FORCEADD OFFPAGE..6
R 2
(-2425 2100);
FORCEPROP 2 LAST $XR0 85 
J 0
(-2211 2100);
DISPLAY 0.638298 (-2211 2100);
PAINT MONO (-2211 2100);
FORCEPROP 2 LAST PATH I741
J 0
(-2200 2150);
DISPLAY 1.021277 (-2200 2150);
DISPLAY INVISIBLE (-2200 2150);
FORCEPROP 1 LAST COMMENT_BODY TRUE
J 2
(-2525 2025);
DISPLAY 0.872340 (-2525 2025);
PAINT GREEN (-2525 2025);
DISPLAY INVISIBLE (-2525 2025);
FORCEPROP 1 LAST OFFPAGE TRUE
J 2
(-2750 1975);
DISPLAY 0.872340 (-2750 1975);
PAINT GREEN (-2750 1975);
DISPLAY INVISIBLE (-2750 1975);
FORCEPROP 2 LAST CDS_LIB mstr_standard
J 0
(-2425 2100);
DISPLAY INVISIBLE (-2425 2100);
FORCEADD TAP..1
(-3025 2900);
FORCEPROP 3 LASTPIN (-3075 2900) SIG_NAME M_A_CPU0_SB_DQ<25>
J 0
(-3065 2910);
DISPLAY 0.659574 (-3065 2910);
PAINT MONO (-3065 2910);
DISPLAY INVISIBLE (-3065 2910);
FORCEPROP 1 LASTPIN (-3075 2900) BN 25
J 0
(-3087 2908);
DISPLAY 0.489362 (-3087 2908);
PAINT MONO (-3087 2908);
FORCEPROP 2 LAST CDS_LIB mstr_standard
J 0
(-3025 2900);
DISPLAY INVISIBLE (-3025 2900);
FORCEPROP 1 LAST BODY_TYPE PLUMBING
J 0
(-3025 2950);
DISPLAY 0.872340 (-3025 2950);
PAINT GREEN (-3025 2950);
DISPLAY INVISIBLE (-3025 2950);
FORCEPROP 1 LAST HDL_TAP TRUE
J 0
(-2700 2775);
DISPLAY 0.872340 (-2700 2775);
DISPLAY INVISIBLE (-2700 2775);
FORCEPROP 1 LAST PATH I742
J 0
(-3027 2900);
DISPLAY 0.872340 (-3027 2900);
PAINT GREEN (-3027 2900);
DISPLAY INVISIBLE (-3027 2900);
FORCEADD TAP..1
(-3025 2850);
FORCEPROP 3 LASTPIN (-3075 2850) SIG_NAME M_A_CPU0_SB_DQ<26>
J 0
(-3065 2860);
DISPLAY 0.659574 (-3065 2860);
PAINT MONO (-3065 2860);
DISPLAY INVISIBLE (-3065 2860);
FORCEPROP 1 LASTPIN (-3075 2850) BN 26
J 0
(-3087 2858);
DISPLAY 0.489362 (-3087 2858);
PAINT MONO (-3087 2858);
FORCEPROP 2 LAST CDS_LIB mstr_standard
J 0
(-3025 2850);
DISPLAY INVISIBLE (-3025 2850);
FORCEPROP 1 LAST BODY_TYPE PLUMBING
J 0
(-3025 2900);
DISPLAY 0.872340 (-3025 2900);
PAINT GREEN (-3025 2900);
DISPLAY INVISIBLE (-3025 2900);
FORCEPROP 1 LAST HDL_TAP TRUE
J 0
(-2700 2725);
DISPLAY 0.872340 (-2700 2725);
DISPLAY INVISIBLE (-2700 2725);
FORCEPROP 1 LAST PATH I743
J 0
(-3027 2850);
DISPLAY 0.872340 (-3027 2850);
PAINT GREEN (-3027 2850);
DISPLAY INVISIBLE (-3027 2850);
FORCEADD TAP..1
(-3025 2950);
FORCEPROP 3 LASTPIN (-3075 2950) SIG_NAME M_A_CPU0_SB_DQ<24>
J 0
(-3065 2960);
DISPLAY 0.659574 (-3065 2960);
PAINT MONO (-3065 2960);
DISPLAY INVISIBLE (-3065 2960);
FORCEPROP 1 LASTPIN (-3075 2950) BN 24
J 0
(-3087 2958);
DISPLAY 0.489362 (-3087 2958);
PAINT MONO (-3087 2958);
FORCEPROP 2 LAST CDS_LIB mstr_standard
J 0
(-3025 2950);
DISPLAY INVISIBLE (-3025 2950);
FORCEPROP 1 LAST BODY_TYPE PLUMBING
J 0
(-3025 3000);
DISPLAY 0.872340 (-3025 3000);
PAINT GREEN (-3025 3000);
DISPLAY INVISIBLE (-3025 3000);
FORCEPROP 1 LAST HDL_TAP TRUE
J 0
(-2700 2825);
DISPLAY 0.872340 (-2700 2825);
DISPLAY INVISIBLE (-2700 2825);
FORCEPROP 1 LAST PATH I744
J 0
(-3027 2950);
DISPLAY 0.872340 (-3027 2950);
PAINT GREEN (-3027 2950);
DISPLAY INVISIBLE (-3027 2950);
FORCEADD TAP..1
(-3025 2750);
FORCEPROP 3 LASTPIN (-3075 2750) SIG_NAME M_A_CPU0_SB_DQ<28>
J 0
(-3065 2760);
DISPLAY 0.659574 (-3065 2760);
PAINT MONO (-3065 2760);
DISPLAY INVISIBLE (-3065 2760);
FORCEPROP 1 LASTPIN (-3075 2750) BN 28
J 0
(-3087 2758);
DISPLAY 0.489362 (-3087 2758);
PAINT MONO (-3087 2758);
FORCEPROP 2 LAST CDS_LIB mstr_standard
J 0
(-3025 2750);
DISPLAY INVISIBLE (-3025 2750);
FORCEPROP 1 LAST BODY_TYPE PLUMBING
J 0
(-3025 2800);
DISPLAY 0.872340 (-3025 2800);
PAINT GREEN (-3025 2800);
DISPLAY INVISIBLE (-3025 2800);
FORCEPROP 1 LAST HDL_TAP TRUE
J 0
(-2700 2625);
DISPLAY 0.872340 (-2700 2625);
DISPLAY INVISIBLE (-2700 2625);
FORCEPROP 1 LAST PATH I745
J 0
(-3027 2750);
DISPLAY 0.872340 (-3027 2750);
PAINT GREEN (-3027 2750);
DISPLAY INVISIBLE (-3027 2750);
FORCEADD TAP..1
(-3025 2800);
FORCEPROP 3 LASTPIN (-3075 2800) SIG_NAME M_A_CPU0_SB_DQ<27>
J 0
(-3065 2810);
DISPLAY 0.659574 (-3065 2810);
PAINT MONO (-3065 2810);
DISPLAY INVISIBLE (-3065 2810);
FORCEPROP 1 LASTPIN (-3075 2800) BN 27
J 0
(-3087 2808);
DISPLAY 0.489362 (-3087 2808);
PAINT MONO (-3087 2808);
FORCEPROP 2 LAST CDS_LIB mstr_standard
J 0
(-3025 2800);
DISPLAY INVISIBLE (-3025 2800);
FORCEPROP 1 LAST BODY_TYPE PLUMBING
J 0
(-3025 2850);
DISPLAY 0.872340 (-3025 2850);
PAINT GREEN (-3025 2850);
DISPLAY INVISIBLE (-3025 2850);
FORCEPROP 1 LAST HDL_TAP TRUE
J 0
(-2700 2675);
DISPLAY 0.872340 (-2700 2675);
DISPLAY INVISIBLE (-2700 2675);
FORCEPROP 1 LAST PATH I746
J 0
(-3027 2800);
DISPLAY 0.872340 (-3027 2800);
PAINT GREEN (-3027 2800);
DISPLAY INVISIBLE (-3027 2800);
FORCEADD TAP..1
(-3025 2600);
FORCEPROP 3 LASTPIN (-3075 2600) SIG_NAME M_A_CPU0_SB_DQ<31>
J 0
(-3065 2610);
DISPLAY 0.659574 (-3065 2610);
PAINT MONO (-3065 2610);
DISPLAY INVISIBLE (-3065 2610);
FORCEPROP 1 LASTPIN (-3075 2600) BN 31
J 0
(-3087 2608);
DISPLAY 0.489362 (-3087 2608);
PAINT MONO (-3087 2608);
FORCEPROP 2 LAST CDS_LIB mstr_standard
J 0
(-3025 2600);
DISPLAY INVISIBLE (-3025 2600);
FORCEPROP 1 LAST BODY_TYPE PLUMBING
J 0
(-3025 2650);
DISPLAY 0.872340 (-3025 2650);
PAINT GREEN (-3025 2650);
DISPLAY INVISIBLE (-3025 2650);
FORCEPROP 1 LAST HDL_TAP TRUE
J 0
(-2700 2475);
DISPLAY 0.872340 (-2700 2475);
DISPLAY INVISIBLE (-2700 2475);
FORCEPROP 1 LAST PATH I747
J 0
(-3027 2600);
DISPLAY 0.872340 (-3027 2600);
PAINT GREEN (-3027 2600);
DISPLAY INVISIBLE (-3027 2600);
FORCEADD TAP..1
(-3025 2650);
FORCEPROP 3 LASTPIN (-3075 2650) SIG_NAME M_A_CPU0_SB_DQ<30>
J 0
(-3065 2660);
DISPLAY 0.659574 (-3065 2660);
PAINT MONO (-3065 2660);
DISPLAY INVISIBLE (-3065 2660);
FORCEPROP 1 LASTPIN (-3075 2650) BN 30
J 0
(-3087 2658);
DISPLAY 0.489362 (-3087 2658);
PAINT MONO (-3087 2658);
FORCEPROP 2 LAST CDS_LIB mstr_standard
J 0
(-3025 2650);
DISPLAY INVISIBLE (-3025 2650);
FORCEPROP 1 LAST BODY_TYPE PLUMBING
J 0
(-3025 2700);
DISPLAY 0.872340 (-3025 2700);
PAINT GREEN (-3025 2700);
DISPLAY INVISIBLE (-3025 2700);
FORCEPROP 1 LAST HDL_TAP TRUE
J 0
(-2700 2525);
DISPLAY 0.872340 (-2700 2525);
DISPLAY INVISIBLE (-2700 2525);
FORCEPROP 1 LAST PATH I748
J 0
(-3027 2650);
DISPLAY 0.872340 (-3027 2650);
PAINT GREEN (-3027 2650);
DISPLAY INVISIBLE (-3027 2650);
FORCEADD TAP..1
(-3025 2700);
FORCEPROP 3 LASTPIN (-3075 2700) SIG_NAME M_A_CPU0_SB_DQ<29>
J 0
(-3065 2710);
DISPLAY 0.659574 (-3065 2710);
PAINT MONO (-3065 2710);
DISPLAY INVISIBLE (-3065 2710);
FORCEPROP 1 LASTPIN (-3075 2700) BN 29
J 0
(-3087 2708);
DISPLAY 0.489362 (-3087 2708);
PAINT MONO (-3087 2708);
FORCEPROP 2 LAST CDS_LIB mstr_standard
J 0
(-3025 2700);
DISPLAY INVISIBLE (-3025 2700);
FORCEPROP 1 LAST BODY_TYPE PLUMBING
J 0
(-3025 2750);
DISPLAY 0.872340 (-3025 2750);
PAINT GREEN (-3025 2750);
DISPLAY INVISIBLE (-3025 2750);
FORCEPROP 1 LAST HDL_TAP TRUE
J 0
(-2700 2575);
DISPLAY 0.872340 (-2700 2575);
DISPLAY INVISIBLE (-2700 2575);
FORCEPROP 1 LAST PATH I749
J 0
(-3027 2700);
DISPLAY 0.872340 (-3027 2700);
PAINT GREEN (-3027 2700);
DISPLAY INVISIBLE (-3027 2700);
FORCEADD TAP..1
(-3025 2500);
FORCEPROP 3 LASTPIN (-3075 2500) SIG_NAME M_A_CPU0_SA_CB<0>
J 0
(-3065 2510);
DISPLAY 0.659574 (-3065 2510);
PAINT MONO (-3065 2510);
DISPLAY INVISIBLE (-3065 2510);
FORCEPROP 1 LASTPIN (-3075 2500) BN 0
J 0
(-3087 2508);
DISPLAY 0.489362 (-3087 2508);
PAINT MONO (-3087 2508);
FORCEPROP 2 LAST CDS_LIB mstr_standard
J 0
(-3025 2500);
DISPLAY INVISIBLE (-3025 2500);
FORCEPROP 1 LAST BODY_TYPE PLUMBING
J 0
(-3025 2550);
DISPLAY 0.872340 (-3025 2550);
PAINT GREEN (-3025 2550);
DISPLAY INVISIBLE (-3025 2550);
FORCEPROP 1 LAST HDL_TAP TRUE
J 0
(-2700 2375);
DISPLAY 0.872340 (-2700 2375);
DISPLAY INVISIBLE (-2700 2375);
FORCEPROP 1 LAST PATH I750
J 0
(-3027 2500);
DISPLAY 0.872340 (-3027 2500);
PAINT GREEN (-3027 2500);
DISPLAY INVISIBLE (-3027 2500);
FORCEADD TAP..1
(-3025 2400);
FORCEPROP 3 LASTPIN (-3075 2400) SIG_NAME M_A_CPU0_SA_CB<2>
J 0
(-3065 2410);
DISPLAY 0.659574 (-3065 2410);
PAINT MONO (-3065 2410);
DISPLAY INVISIBLE (-3065 2410);
FORCEPROP 1 LASTPIN (-3075 2400) BN 2
J 0
(-3087 2408);
DISPLAY 0.489362 (-3087 2408);
PAINT MONO (-3087 2408);
FORCEPROP 2 LAST CDS_LIB mstr_standard
J 0
(-3025 2400);
DISPLAY INVISIBLE (-3025 2400);
FORCEPROP 1 LAST BODY_TYPE PLUMBING
J 0
(-3025 2450);
DISPLAY 0.872340 (-3025 2450);
PAINT GREEN (-3025 2450);
DISPLAY INVISIBLE (-3025 2450);
FORCEPROP 1 LAST HDL_TAP TRUE
J 0
(-2700 2275);
DISPLAY 0.872340 (-2700 2275);
DISPLAY INVISIBLE (-2700 2275);
FORCEPROP 1 LAST PATH I751
J 0
(-3027 2400);
DISPLAY 0.872340 (-3027 2400);
PAINT GREEN (-3027 2400);
DISPLAY INVISIBLE (-3027 2400);
FORCEADD TAP..1
(-3025 2450);
FORCEPROP 3 LASTPIN (-3075 2450) SIG_NAME M_A_CPU0_SA_CB<1>
J 0
(-3065 2460);
DISPLAY 0.659574 (-3065 2460);
PAINT MONO (-3065 2460);
DISPLAY INVISIBLE (-3065 2460);
FORCEPROP 1 LASTPIN (-3075 2450) BN 1
J 0
(-3087 2458);
DISPLAY 0.489362 (-3087 2458);
PAINT MONO (-3087 2458);
FORCEPROP 2 LAST CDS_LIB mstr_standard
J 0
(-3025 2450);
DISPLAY INVISIBLE (-3025 2450);
FORCEPROP 1 LAST BODY_TYPE PLUMBING
J 0
(-3025 2500);
DISPLAY 0.872340 (-3025 2500);
PAINT GREEN (-3025 2500);
DISPLAY INVISIBLE (-3025 2500);
FORCEPROP 1 LAST HDL_TAP TRUE
J 0
(-2700 2325);
DISPLAY 0.872340 (-2700 2325);
DISPLAY INVISIBLE (-2700 2325);
FORCEPROP 1 LAST PATH I752
J 0
(-3027 2450);
DISPLAY 0.872340 (-3027 2450);
PAINT GREEN (-3027 2450);
DISPLAY INVISIBLE (-3027 2450);
FORCEADD TAP..1
(-3025 2350);
FORCEPROP 3 LASTPIN (-3075 2350) SIG_NAME M_A_CPU0_SA_CB<3>
J 0
(-3065 2360);
DISPLAY 0.659574 (-3065 2360);
PAINT MONO (-3065 2360);
DISPLAY INVISIBLE (-3065 2360);
FORCEPROP 1 LASTPIN (-3075 2350) BN 3
J 0
(-3087 2358);
DISPLAY 0.489362 (-3087 2358);
PAINT MONO (-3087 2358);
FORCEPROP 2 LAST CDS_LIB mstr_standard
J 0
(-3025 2350);
DISPLAY INVISIBLE (-3025 2350);
FORCEPROP 1 LAST BODY_TYPE PLUMBING
J 0
(-3025 2400);
DISPLAY 0.872340 (-3025 2400);
PAINT GREEN (-3025 2400);
DISPLAY INVISIBLE (-3025 2400);
FORCEPROP 1 LAST HDL_TAP TRUE
J 0
(-2700 2225);
DISPLAY 0.872340 (-2700 2225);
DISPLAY INVISIBLE (-2700 2225);
FORCEPROP 1 LAST PATH I753
J 0
(-3027 2350);
DISPLAY 0.872340 (-3027 2350);
PAINT GREEN (-3027 2350);
DISPLAY INVISIBLE (-3027 2350);
FORCEADD TAP..1
(-3025 2300);
FORCEPROP 3 LASTPIN (-3075 2300) SIG_NAME M_A_CPU0_SA_CB<4>
J 0
(-3065 2310);
DISPLAY 0.659574 (-3065 2310);
PAINT MONO (-3065 2310);
DISPLAY INVISIBLE (-3065 2310);
FORCEPROP 1 LASTPIN (-3075 2300) BN 4
J 0
(-3087 2308);
DISPLAY 0.489362 (-3087 2308);
PAINT MONO (-3087 2308);
FORCEPROP 2 LAST CDS_LIB mstr_standard
J 0
(-3025 2300);
DISPLAY INVISIBLE (-3025 2300);
FORCEPROP 1 LAST BODY_TYPE PLUMBING
J 0
(-3025 2350);
DISPLAY 0.872340 (-3025 2350);
PAINT GREEN (-3025 2350);
DISPLAY INVISIBLE (-3025 2350);
FORCEPROP 1 LAST HDL_TAP TRUE
J 0
(-2700 2175);
DISPLAY 0.872340 (-2700 2175);
DISPLAY INVISIBLE (-2700 2175);
FORCEPROP 1 LAST PATH I754
J 0
(-3027 2300);
DISPLAY 0.872340 (-3027 2300);
PAINT GREEN (-3027 2300);
DISPLAY INVISIBLE (-3027 2300);
FORCEADD TAP..1
(-3025 2250);
FORCEPROP 3 LASTPIN (-3075 2250) SIG_NAME M_A_CPU0_SA_CB<5>
J 0
(-3065 2260);
DISPLAY 0.659574 (-3065 2260);
PAINT MONO (-3065 2260);
DISPLAY INVISIBLE (-3065 2260);
FORCEPROP 1 LASTPIN (-3075 2250) BN 5
J 0
(-3087 2258);
DISPLAY 0.489362 (-3087 2258);
PAINT MONO (-3087 2258);
FORCEPROP 2 LAST CDS_LIB mstr_standard
J 0
(-3025 2250);
DISPLAY INVISIBLE (-3025 2250);
FORCEPROP 1 LAST BODY_TYPE PLUMBING
J 0
(-3025 2300);
DISPLAY 0.872340 (-3025 2300);
PAINT GREEN (-3025 2300);
DISPLAY INVISIBLE (-3025 2300);
FORCEPROP 1 LAST HDL_TAP TRUE
J 0
(-2700 2125);
DISPLAY 0.872340 (-2700 2125);
DISPLAY INVISIBLE (-2700 2125);
FORCEPROP 1 LAST PATH I755
J 0
(-3027 2250);
DISPLAY 0.872340 (-3027 2250);
PAINT GREEN (-3027 2250);
DISPLAY INVISIBLE (-3027 2250);
FORCEADD TAP..1
(-3025 2050);
FORCEPROP 3 LASTPIN (-3075 2050) SIG_NAME M_A_CPU0_SB_CB<0>
J 0
(-3065 2060);
DISPLAY 0.659574 (-3065 2060);
PAINT MONO (-3065 2060);
DISPLAY INVISIBLE (-3065 2060);
FORCEPROP 1 LASTPIN (-3075 2050) BN 0
J 0
(-3087 2058);
DISPLAY 0.489362 (-3087 2058);
PAINT MONO (-3087 2058);
FORCEPROP 2 LAST CDS_LIB mstr_standard
J 0
(-3025 2050);
DISPLAY INVISIBLE (-3025 2050);
FORCEPROP 1 LAST BODY_TYPE PLUMBING
J 0
(-3025 2100);
DISPLAY 0.872340 (-3025 2100);
PAINT GREEN (-3025 2100);
DISPLAY INVISIBLE (-3025 2100);
FORCEPROP 1 LAST HDL_TAP TRUE
J 0
(-2700 1925);
DISPLAY 0.872340 (-2700 1925);
DISPLAY INVISIBLE (-2700 1925);
FORCEPROP 1 LAST PATH I756
J 0
(-3027 2050);
DISPLAY 0.872340 (-3027 2050);
PAINT GREEN (-3027 2050);
DISPLAY INVISIBLE (-3027 2050);
FORCEADD TAP..1
(-3025 2150);
FORCEPROP 3 LASTPIN (-3075 2150) SIG_NAME M_A_CPU0_SA_CB<7>
J 0
(-3065 2160);
DISPLAY 0.659574 (-3065 2160);
PAINT MONO (-3065 2160);
DISPLAY INVISIBLE (-3065 2160);
FORCEPROP 1 LASTPIN (-3075 2150) BN 7
J 0
(-3087 2158);
DISPLAY 0.489362 (-3087 2158);
PAINT MONO (-3087 2158);
FORCEPROP 2 LAST CDS_LIB mstr_standard
J 0
(-3025 2150);
DISPLAY INVISIBLE (-3025 2150);
FORCEPROP 1 LAST BODY_TYPE PLUMBING
J 0
(-3025 2200);
DISPLAY 0.872340 (-3025 2200);
PAINT GREEN (-3025 2200);
DISPLAY INVISIBLE (-3025 2200);
FORCEPROP 1 LAST HDL_TAP TRUE
J 0
(-2700 2025);
DISPLAY 0.872340 (-2700 2025);
DISPLAY INVISIBLE (-2700 2025);
FORCEPROP 1 LAST PATH I757
J 0
(-3027 2150);
DISPLAY 0.872340 (-3027 2150);
PAINT GREEN (-3027 2150);
DISPLAY INVISIBLE (-3027 2150);
FORCEADD TAP..1
(-3025 2200);
FORCEPROP 3 LASTPIN (-3075 2200) SIG_NAME M_A_CPU0_SA_CB<6>
J 0
(-3065 2210);
DISPLAY 0.659574 (-3065 2210);
PAINT MONO (-3065 2210);
DISPLAY INVISIBLE (-3065 2210);
FORCEPROP 1 LASTPIN (-3075 2200) BN 6
J 0
(-3087 2208);
DISPLAY 0.489362 (-3087 2208);
PAINT MONO (-3087 2208);
FORCEPROP 2 LAST CDS_LIB mstr_standard
J 0
(-3025 2200);
DISPLAY INVISIBLE (-3025 2200);
FORCEPROP 1 LAST BODY_TYPE PLUMBING
J 0
(-3025 2250);
DISPLAY 0.872340 (-3025 2250);
PAINT GREEN (-3025 2250);
DISPLAY INVISIBLE (-3025 2250);
FORCEPROP 1 LAST HDL_TAP TRUE
J 0
(-2700 2075);
DISPLAY 0.872340 (-2700 2075);
DISPLAY INVISIBLE (-2700 2075);
FORCEPROP 1 LAST PATH I758
J 0
(-3027 2200);
DISPLAY 0.872340 (-3027 2200);
PAINT GREEN (-3027 2200);
DISPLAY INVISIBLE (-3027 2200);
FORCEADD TAP..1
(-3025 2000);
FORCEPROP 3 LASTPIN (-3075 2000) SIG_NAME M_A_CPU0_SB_CB<1>
J 0
(-3065 2010);
DISPLAY 0.659574 (-3065 2010);
PAINT MONO (-3065 2010);
DISPLAY INVISIBLE (-3065 2010);
FORCEPROP 1 LASTPIN (-3075 2000) BN 1
J 0
(-3087 2008);
DISPLAY 0.489362 (-3087 2008);
PAINT MONO (-3087 2008);
FORCEPROP 2 LAST CDS_LIB mstr_standard
J 0
(-3025 2000);
DISPLAY INVISIBLE (-3025 2000);
FORCEPROP 1 LAST BODY_TYPE PLUMBING
J 0
(-3025 2050);
DISPLAY 0.872340 (-3025 2050);
PAINT GREEN (-3025 2050);
DISPLAY INVISIBLE (-3025 2050);
FORCEPROP 1 LAST HDL_TAP TRUE
J 0
(-2700 1875);
DISPLAY 0.872340 (-2700 1875);
DISPLAY INVISIBLE (-2700 1875);
FORCEPROP 1 LAST PATH I759
J 0
(-3027 2000);
DISPLAY 0.872340 (-3027 2000);
PAINT GREEN (-3027 2000);
DISPLAY INVISIBLE (-3027 2000);
FORCEADD TAP..1
(-3025 1950);
FORCEPROP 3 LASTPIN (-3075 1950) SIG_NAME M_A_CPU0_SB_CB<2>
J 0
(-3065 1960);
DISPLAY 0.659574 (-3065 1960);
PAINT MONO (-3065 1960);
DISPLAY INVISIBLE (-3065 1960);
FORCEPROP 1 LASTPIN (-3075 1950) BN 2
J 0
(-3087 1958);
DISPLAY 0.489362 (-3087 1958);
PAINT MONO (-3087 1958);
FORCEPROP 2 LAST CDS_LIB mstr_standard
J 0
(-3025 1950);
DISPLAY INVISIBLE (-3025 1950);
FORCEPROP 1 LAST BODY_TYPE PLUMBING
J 0
(-3025 2000);
DISPLAY 0.872340 (-3025 2000);
PAINT GREEN (-3025 2000);
DISPLAY INVISIBLE (-3025 2000);
FORCEPROP 1 LAST HDL_TAP TRUE
J 0
(-2700 1825);
DISPLAY 0.872340 (-2700 1825);
DISPLAY INVISIBLE (-2700 1825);
FORCEPROP 1 LAST PATH I760
J 0
(-3027 1950);
DISPLAY 0.872340 (-3027 1950);
PAINT GREEN (-3027 1950);
DISPLAY INVISIBLE (-3027 1950);
FORCEADD TAP..1
(-3025 1900);
FORCEPROP 3 LASTPIN (-3075 1900) SIG_NAME M_A_CPU0_SB_CB<3>
J 0
(-3065 1910);
DISPLAY 0.659574 (-3065 1910);
PAINT MONO (-3065 1910);
DISPLAY INVISIBLE (-3065 1910);
FORCEPROP 1 LASTPIN (-3075 1900) BN 3
J 0
(-3087 1908);
DISPLAY 0.489362 (-3087 1908);
PAINT MONO (-3087 1908);
FORCEPROP 2 LAST CDS_LIB mstr_standard
J 0
(-3025 1900);
DISPLAY INVISIBLE (-3025 1900);
FORCEPROP 1 LAST BODY_TYPE PLUMBING
J 0
(-3025 1950);
DISPLAY 0.872340 (-3025 1950);
PAINT GREEN (-3025 1950);
DISPLAY INVISIBLE (-3025 1950);
FORCEPROP 1 LAST HDL_TAP TRUE
J 0
(-2700 1775);
DISPLAY 0.872340 (-2700 1775);
DISPLAY INVISIBLE (-2700 1775);
FORCEPROP 1 LAST PATH I761
J 0
(-3027 1900);
DISPLAY 0.872340 (-3027 1900);
PAINT GREEN (-3027 1900);
DISPLAY INVISIBLE (-3027 1900);
FORCEADD TAP..1
(-3025 1850);
FORCEPROP 3 LASTPIN (-3075 1850) SIG_NAME M_A_CPU0_SB_CB<4>
J 0
(-3065 1860);
DISPLAY 0.659574 (-3065 1860);
PAINT MONO (-3065 1860);
DISPLAY INVISIBLE (-3065 1860);
FORCEPROP 1 LASTPIN (-3075 1850) BN 4
J 0
(-3087 1858);
DISPLAY 0.489362 (-3087 1858);
PAINT MONO (-3087 1858);
FORCEPROP 2 LAST CDS_LIB mstr_standard
J 0
(-3025 1850);
DISPLAY INVISIBLE (-3025 1850);
FORCEPROP 1 LAST BODY_TYPE PLUMBING
J 0
(-3025 1900);
DISPLAY 0.872340 (-3025 1900);
PAINT GREEN (-3025 1900);
DISPLAY INVISIBLE (-3025 1900);
FORCEPROP 1 LAST HDL_TAP TRUE
J 0
(-2700 1725);
DISPLAY 0.872340 (-2700 1725);
DISPLAY INVISIBLE (-2700 1725);
FORCEPROP 1 LAST PATH I762
J 0
(-3027 1850);
DISPLAY 0.872340 (-3027 1850);
PAINT GREEN (-3027 1850);
DISPLAY INVISIBLE (-3027 1850);
FORCEADD TAP..1
(-3025 1800);
FORCEPROP 3 LASTPIN (-3075 1800) SIG_NAME M_A_CPU0_SB_CB<5>
J 0
(-3065 1810);
DISPLAY 0.659574 (-3065 1810);
PAINT MONO (-3065 1810);
DISPLAY INVISIBLE (-3065 1810);
FORCEPROP 1 LASTPIN (-3075 1800) BN 5
J 0
(-3087 1808);
DISPLAY 0.489362 (-3087 1808);
PAINT MONO (-3087 1808);
FORCEPROP 2 LAST CDS_LIB mstr_standard
J 0
(-3025 1800);
DISPLAY INVISIBLE (-3025 1800);
FORCEPROP 1 LAST BODY_TYPE PLUMBING
J 0
(-3025 1850);
DISPLAY 0.872340 (-3025 1850);
PAINT GREEN (-3025 1850);
DISPLAY INVISIBLE (-3025 1850);
FORCEPROP 1 LAST HDL_TAP TRUE
J 0
(-2700 1675);
DISPLAY 0.872340 (-2700 1675);
DISPLAY INVISIBLE (-2700 1675);
FORCEPROP 1 LAST PATH I763
J 0
(-3027 1800);
DISPLAY 0.872340 (-3027 1800);
PAINT GREEN (-3027 1800);
DISPLAY INVISIBLE (-3027 1800);
FORCEADD TAP..1
(-3025 1750);
FORCEPROP 3 LASTPIN (-3075 1750) SIG_NAME M_A_CPU0_SB_CB<6>
J 0
(-3065 1760);
DISPLAY 0.659574 (-3065 1760);
PAINT MONO (-3065 1760);
DISPLAY INVISIBLE (-3065 1760);
FORCEPROP 1 LASTPIN (-3075 1750) BN 6
J 0
(-3087 1758);
DISPLAY 0.489362 (-3087 1758);
PAINT MONO (-3087 1758);
FORCEPROP 2 LAST CDS_LIB mstr_standard
J 0
(-3025 1750);
DISPLAY INVISIBLE (-3025 1750);
FORCEPROP 1 LAST BODY_TYPE PLUMBING
J 0
(-3025 1800);
DISPLAY 0.872340 (-3025 1800);
PAINT GREEN (-3025 1800);
DISPLAY INVISIBLE (-3025 1800);
FORCEPROP 1 LAST HDL_TAP TRUE
J 0
(-2700 1625);
DISPLAY 0.872340 (-2700 1625);
DISPLAY INVISIBLE (-2700 1625);
FORCEPROP 1 LAST PATH I764
J 0
(-3027 1750);
DISPLAY 0.872340 (-3027 1750);
PAINT GREEN (-3027 1750);
DISPLAY INVISIBLE (-3027 1750);
FORCEADD TAP..1
(-3025 1700);
FORCEPROP 3 LASTPIN (-3075 1700) SIG_NAME M_A_CPU0_SB_CB<7>
J 0
(-3065 1710);
DISPLAY 0.659574 (-3065 1710);
PAINT MONO (-3065 1710);
DISPLAY INVISIBLE (-3065 1710);
FORCEPROP 1 LASTPIN (-3075 1700) BN 7
J 0
(-3087 1708);
DISPLAY 0.489362 (-3087 1708);
PAINT MONO (-3087 1708);
FORCEPROP 2 LAST CDS_LIB mstr_standard
J 0
(-3025 1700);
DISPLAY INVISIBLE (-3025 1700);
FORCEPROP 1 LAST BODY_TYPE PLUMBING
J 0
(-3025 1750);
DISPLAY 0.872340 (-3025 1750);
PAINT GREEN (-3025 1750);
DISPLAY INVISIBLE (-3025 1750);
FORCEPROP 1 LAST HDL_TAP TRUE
J 0
(-2700 1575);
DISPLAY 0.872340 (-2700 1575);
DISPLAY INVISIBLE (-2700 1575);
FORCEPROP 1 LAST PATH I765
J 0
(-3027 1700);
DISPLAY 0.872340 (-3027 1700);
PAINT GREEN (-3027 1700);
DISPLAY INVISIBLE (-3027 1700);
FORCEADD TAP..1
R 2
(-5550 6100);
FORCEPROP 3 LASTPIN (-5500 6100) SIG_NAME M_A_CPU0_SA_DQS_DP<0>
J 0
(-5490 6110);
DISPLAY 0.659574 (-5490 6110);
PAINT MONO (-5490 6110);
DISPLAY INVISIBLE (-5490 6110);
FORCEPROP 1 LASTPIN (-5500 6100) BN 0
J 2
(-5488 6108);
DISPLAY 0.489362 (-5488 6108);
PAINT MONO (-5488 6108);
FORCEPROP 2 LAST CDS_LIB mstr_standard
J 0
(-5550 6100);
DISPLAY INVISIBLE (-5550 6100);
FORCEPROP 1 LAST BODY_TYPE PLUMBING
J 2
(-5550 6150);
DISPLAY 0.872340 (-5550 6150);
PAINT GREEN (-5550 6150);
DISPLAY INVISIBLE (-5550 6150);
FORCEPROP 1 LAST HDL_TAP TRUE
J 2
(-5875 5975);
DISPLAY 0.872340 (-5875 5975);
DISPLAY INVISIBLE (-5875 5975);
FORCEPROP 1 LAST PATH I766
J 2
(-5548 6100);
DISPLAY 0.872340 (-5548 6100);
PAINT GREEN (-5548 6100);
DISPLAY INVISIBLE (-5548 6100);
FORCEADD TAP..1
R 2
(-5550 6000);
FORCEPROP 3 LASTPIN (-5500 6000) SIG_NAME M_A_CPU0_SA_DQS_DP<1>
J 0
(-5490 6010);
DISPLAY 0.659574 (-5490 6010);
PAINT MONO (-5490 6010);
DISPLAY INVISIBLE (-5490 6010);
FORCEPROP 1 LASTPIN (-5500 6000) BN 1
J 2
(-5488 6008);
DISPLAY 0.489362 (-5488 6008);
PAINT MONO (-5488 6008);
FORCEPROP 2 LAST CDS_LIB mstr_standard
J 0
(-5550 6000);
DISPLAY INVISIBLE (-5550 6000);
FORCEPROP 1 LAST BODY_TYPE PLUMBING
J 2
(-5550 6050);
DISPLAY 0.872340 (-5550 6050);
PAINT GREEN (-5550 6050);
DISPLAY INVISIBLE (-5550 6050);
FORCEPROP 1 LAST HDL_TAP TRUE
J 2
(-5875 5875);
DISPLAY 0.872340 (-5875 5875);
DISPLAY INVISIBLE (-5875 5875);
FORCEPROP 1 LAST PATH I767
J 2
(-5548 6000);
DISPLAY 0.872340 (-5548 6000);
PAINT GREEN (-5548 6000);
DISPLAY INVISIBLE (-5548 6000);
FORCEADD TAP..1
R 2
(-5550 5900);
FORCEPROP 3 LASTPIN (-5500 5900) SIG_NAME M_A_CPU0_SA_DQS_DP<2>
J 0
(-5490 5910);
DISPLAY 0.659574 (-5490 5910);
PAINT MONO (-5490 5910);
DISPLAY INVISIBLE (-5490 5910);
FORCEPROP 1 LASTPIN (-5500 5900) BN 2
J 2
(-5488 5908);
DISPLAY 0.489362 (-5488 5908);
PAINT MONO (-5488 5908);
FORCEPROP 2 LAST CDS_LIB mstr_standard
J 0
(-5550 5900);
DISPLAY INVISIBLE (-5550 5900);
FORCEPROP 1 LAST BODY_TYPE PLUMBING
J 2
(-5550 5950);
DISPLAY 0.872340 (-5550 5950);
PAINT GREEN (-5550 5950);
DISPLAY INVISIBLE (-5550 5950);
FORCEPROP 1 LAST HDL_TAP TRUE
J 2
(-5875 5775);
DISPLAY 0.872340 (-5875 5775);
DISPLAY INVISIBLE (-5875 5775);
FORCEPROP 1 LAST PATH I768
J 2
(-5548 5900);
DISPLAY 0.872340 (-5548 5900);
PAINT GREEN (-5548 5900);
DISPLAY INVISIBLE (-5548 5900);
FORCEADD TAP..1
R 2
(-5550 5800);
FORCEPROP 3 LASTPIN (-5500 5800) SIG_NAME M_A_CPU0_SA_DQS_DP<3>
J 0
(-5490 5810);
DISPLAY 0.659574 (-5490 5810);
PAINT MONO (-5490 5810);
DISPLAY INVISIBLE (-5490 5810);
FORCEPROP 1 LASTPIN (-5500 5800) BN 3
J 2
(-5488 5808);
DISPLAY 0.489362 (-5488 5808);
PAINT MONO (-5488 5808);
FORCEPROP 2 LAST CDS_LIB mstr_standard
J 0
(-5550 5800);
DISPLAY INVISIBLE (-5550 5800);
FORCEPROP 1 LAST BODY_TYPE PLUMBING
J 2
(-5550 5850);
DISPLAY 0.872340 (-5550 5850);
PAINT GREEN (-5550 5850);
DISPLAY INVISIBLE (-5550 5850);
FORCEPROP 1 LAST HDL_TAP TRUE
J 2
(-5875 5675);
DISPLAY 0.872340 (-5875 5675);
DISPLAY INVISIBLE (-5875 5675);
FORCEPROP 1 LAST PATH I769
J 2
(-5548 5800);
DISPLAY 0.872340 (-5548 5800);
PAINT GREEN (-5548 5800);
DISPLAY INVISIBLE (-5548 5800);
FORCEADD TAP..1
R 2
(-5550 5700);
FORCEPROP 3 LASTPIN (-5500 5700) SIG_NAME M_A_CPU0_SA_DQS_DP<4>
J 0
(-5490 5710);
DISPLAY 0.659574 (-5490 5710);
PAINT MONO (-5490 5710);
DISPLAY INVISIBLE (-5490 5710);
FORCEPROP 1 LASTPIN (-5500 5700) BN 4
J 2
(-5488 5708);
DISPLAY 0.489362 (-5488 5708);
PAINT MONO (-5488 5708);
FORCEPROP 2 LAST CDS_LIB mstr_standard
J 0
(-5550 5700);
DISPLAY INVISIBLE (-5550 5700);
FORCEPROP 1 LAST BODY_TYPE PLUMBING
J 2
(-5550 5750);
DISPLAY 0.872340 (-5550 5750);
PAINT GREEN (-5550 5750);
DISPLAY INVISIBLE (-5550 5750);
FORCEPROP 1 LAST HDL_TAP TRUE
J 2
(-5875 5575);
DISPLAY 0.872340 (-5875 5575);
DISPLAY INVISIBLE (-5875 5575);
FORCEPROP 1 LAST PATH I770
J 2
(-5548 5700);
DISPLAY 0.872340 (-5548 5700);
PAINT GREEN (-5548 5700);
DISPLAY INVISIBLE (-5548 5700);
FORCEADD TAP..1
R 2
(-5550 5600);
FORCEPROP 3 LASTPIN (-5500 5600) SIG_NAME M_A_CPU0_SA_DQS_DP<5>
J 0
(-5490 5610);
DISPLAY 0.659574 (-5490 5610);
PAINT MONO (-5490 5610);
DISPLAY INVISIBLE (-5490 5610);
FORCEPROP 1 LASTPIN (-5500 5600) BN 5
J 2
(-5488 5608);
DISPLAY 0.489362 (-5488 5608);
PAINT MONO (-5488 5608);
FORCEPROP 2 LAST CDS_LIB mstr_standard
J 0
(-5550 5600);
DISPLAY INVISIBLE (-5550 5600);
FORCEPROP 1 LAST BODY_TYPE PLUMBING
J 2
(-5550 5650);
DISPLAY 0.872340 (-5550 5650);
PAINT GREEN (-5550 5650);
DISPLAY INVISIBLE (-5550 5650);
FORCEPROP 1 LAST HDL_TAP TRUE
J 2
(-5875 5475);
DISPLAY 0.872340 (-5875 5475);
DISPLAY INVISIBLE (-5875 5475);
FORCEPROP 1 LAST PATH I771
J 2
(-5548 5600);
DISPLAY 0.872340 (-5548 5600);
PAINT GREEN (-5548 5600);
DISPLAY INVISIBLE (-5548 5600);
FORCEADD TAP..1
R 2
(-5550 5500);
FORCEPROP 3 LASTPIN (-5500 5500) SIG_NAME M_A_CPU0_SA_DQS_DP<6>
J 0
(-5490 5510);
DISPLAY 0.659574 (-5490 5510);
PAINT MONO (-5490 5510);
DISPLAY INVISIBLE (-5490 5510);
FORCEPROP 1 LASTPIN (-5500 5500) BN 6
J 2
(-5488 5508);
DISPLAY 0.489362 (-5488 5508);
PAINT MONO (-5488 5508);
FORCEPROP 2 LAST CDS_LIB mstr_standard
J 0
(-5550 5500);
DISPLAY INVISIBLE (-5550 5500);
FORCEPROP 1 LAST BODY_TYPE PLUMBING
J 2
(-5550 5550);
DISPLAY 0.872340 (-5550 5550);
PAINT GREEN (-5550 5550);
DISPLAY INVISIBLE (-5550 5550);
FORCEPROP 1 LAST HDL_TAP TRUE
J 2
(-5875 5375);
DISPLAY 0.872340 (-5875 5375);
DISPLAY INVISIBLE (-5875 5375);
FORCEPROP 1 LAST PATH I772
J 2
(-5548 5500);
DISPLAY 0.872340 (-5548 5500);
PAINT GREEN (-5548 5500);
DISPLAY INVISIBLE (-5548 5500);
FORCEADD TAP..1
R 2
(-5550 5400);
FORCEPROP 3 LASTPIN (-5500 5400) SIG_NAME M_A_CPU0_SA_DQS_DP<7>
J 0
(-5490 5410);
DISPLAY 0.659574 (-5490 5410);
PAINT MONO (-5490 5410);
DISPLAY INVISIBLE (-5490 5410);
FORCEPROP 1 LASTPIN (-5500 5400) BN 7
J 2
(-5488 5408);
DISPLAY 0.489362 (-5488 5408);
PAINT MONO (-5488 5408);
FORCEPROP 2 LAST CDS_LIB mstr_standard
J 0
(-5550 5400);
DISPLAY INVISIBLE (-5550 5400);
FORCEPROP 1 LAST BODY_TYPE PLUMBING
J 2
(-5550 5450);
DISPLAY 0.872340 (-5550 5450);
PAINT GREEN (-5550 5450);
DISPLAY INVISIBLE (-5550 5450);
FORCEPROP 1 LAST HDL_TAP TRUE
J 2
(-5875 5275);
DISPLAY 0.872340 (-5875 5275);
DISPLAY INVISIBLE (-5875 5275);
FORCEPROP 1 LAST PATH I773
J 2
(-5548 5400);
DISPLAY 0.872340 (-5548 5400);
PAINT GREEN (-5548 5400);
DISPLAY INVISIBLE (-5548 5400);
FORCEADD TAP..1
R 2
(-5550 5300);
FORCEPROP 3 LASTPIN (-5500 5300) SIG_NAME M_A_CPU0_SA_DQS_DP<8>
J 0
(-5490 5310);
DISPLAY 0.659574 (-5490 5310);
PAINT MONO (-5490 5310);
DISPLAY INVISIBLE (-5490 5310);
FORCEPROP 1 LASTPIN (-5500 5300) BN 8
J 2
(-5488 5308);
DISPLAY 0.489362 (-5488 5308);
PAINT MONO (-5488 5308);
FORCEPROP 2 LAST CDS_LIB mstr_standard
J 0
(-5550 5300);
DISPLAY INVISIBLE (-5550 5300);
FORCEPROP 1 LAST BODY_TYPE PLUMBING
J 2
(-5550 5350);
DISPLAY 0.872340 (-5550 5350);
PAINT GREEN (-5550 5350);
DISPLAY INVISIBLE (-5550 5350);
FORCEPROP 1 LAST HDL_TAP TRUE
J 2
(-5875 5175);
DISPLAY 0.872340 (-5875 5175);
DISPLAY INVISIBLE (-5875 5175);
FORCEPROP 1 LAST PATH I774
J 2
(-5548 5300);
DISPLAY 0.872340 (-5548 5300);
PAINT GREEN (-5548 5300);
DISPLAY INVISIBLE (-5548 5300);
FORCEADD TAP..1
R 2
(-5550 5200);
FORCEPROP 3 LASTPIN (-5500 5200) SIG_NAME M_A_CPU0_SA_DQS_DP<9>
J 0
(-5490 5210);
DISPLAY 0.659574 (-5490 5210);
PAINT MONO (-5490 5210);
DISPLAY INVISIBLE (-5490 5210);
FORCEPROP 1 LASTPIN (-5500 5200) BN 9
J 2
(-5488 5208);
DISPLAY 0.489362 (-5488 5208);
PAINT MONO (-5488 5208);
FORCEPROP 2 LAST CDS_LIB mstr_standard
J 0
(-5550 5200);
DISPLAY INVISIBLE (-5550 5200);
FORCEPROP 1 LAST BODY_TYPE PLUMBING
J 2
(-5550 5250);
DISPLAY 0.872340 (-5550 5250);
PAINT GREEN (-5550 5250);
DISPLAY INVISIBLE (-5550 5250);
FORCEPROP 1 LAST HDL_TAP TRUE
J 2
(-5875 5075);
DISPLAY 0.872340 (-5875 5075);
DISPLAY INVISIBLE (-5875 5075);
FORCEPROP 1 LAST PATH I775
J 2
(-5548 5200);
DISPLAY 0.872340 (-5548 5200);
PAINT GREEN (-5548 5200);
DISPLAY INVISIBLE (-5548 5200);
FORCEADD TAP..1
R 2
(-5750 5950);
FORCEPROP 3 LASTPIN (-5700 5950) SIG_NAME M_A_CPU0_SA_DQS_DN<1>
J 0
(-5690 5960);
DISPLAY 0.659574 (-5690 5960);
PAINT MONO (-5690 5960);
DISPLAY INVISIBLE (-5690 5960);
FORCEPROP 1 LASTPIN (-5700 5950) BN 1
J 2
(-5688 5958);
DISPLAY 0.489362 (-5688 5958);
PAINT MONO (-5688 5958);
FORCEPROP 2 LAST CDS_LIB mstr_standard
J 0
(-5750 5950);
DISPLAY INVISIBLE (-5750 5950);
FORCEPROP 1 LAST BODY_TYPE PLUMBING
J 2
(-5750 6000);
DISPLAY 0.872340 (-5750 6000);
PAINT GREEN (-5750 6000);
DISPLAY INVISIBLE (-5750 6000);
FORCEPROP 1 LAST HDL_TAP TRUE
J 2
(-6075 5825);
DISPLAY 0.872340 (-6075 5825);
DISPLAY INVISIBLE (-6075 5825);
FORCEPROP 1 LAST PATH I776
J 2
(-5748 5950);
DISPLAY 0.872340 (-5748 5950);
PAINT GREEN (-5748 5950);
DISPLAY INVISIBLE (-5748 5950);
FORCEADD TAP..1
R 2
(-5750 6050);
FORCEPROP 3 LASTPIN (-5700 6050) SIG_NAME M_A_CPU0_SA_DQS_DN<0>
J 0
(-5690 6060);
DISPLAY 0.659574 (-5690 6060);
PAINT MONO (-5690 6060);
DISPLAY INVISIBLE (-5690 6060);
FORCEPROP 1 LASTPIN (-5700 6050) BN 0
J 2
(-5688 6058);
DISPLAY 0.489362 (-5688 6058);
PAINT MONO (-5688 6058);
FORCEPROP 2 LAST CDS_LIB mstr_standard
J 0
(-5750 6050);
DISPLAY INVISIBLE (-5750 6050);
FORCEPROP 1 LAST BODY_TYPE PLUMBING
J 2
(-5750 6100);
DISPLAY 0.872340 (-5750 6100);
PAINT GREEN (-5750 6100);
DISPLAY INVISIBLE (-5750 6100);
FORCEPROP 1 LAST HDL_TAP TRUE
J 2
(-6075 5925);
DISPLAY 0.872340 (-6075 5925);
DISPLAY INVISIBLE (-6075 5925);
FORCEPROP 1 LAST PATH I777
J 2
(-5748 6050);
DISPLAY 0.872340 (-5748 6050);
PAINT GREEN (-5748 6050);
DISPLAY INVISIBLE (-5748 6050);
FORCEADD TAP..1
R 2
(-5750 5650);
FORCEPROP 3 LASTPIN (-5700 5650) SIG_NAME M_A_CPU0_SA_DQS_DN<4>
J 0
(-5690 5660);
DISPLAY 0.659574 (-5690 5660);
PAINT MONO (-5690 5660);
DISPLAY INVISIBLE (-5690 5660);
FORCEPROP 1 LASTPIN (-5700 5650) BN 4
J 2
(-5688 5658);
DISPLAY 0.489362 (-5688 5658);
PAINT MONO (-5688 5658);
FORCEPROP 2 LAST CDS_LIB mstr_standard
J 0
(-5750 5650);
DISPLAY INVISIBLE (-5750 5650);
FORCEPROP 1 LAST BODY_TYPE PLUMBING
J 2
(-5750 5700);
DISPLAY 0.872340 (-5750 5700);
PAINT GREEN (-5750 5700);
DISPLAY INVISIBLE (-5750 5700);
FORCEPROP 1 LAST HDL_TAP TRUE
J 2
(-6075 5525);
DISPLAY 0.872340 (-6075 5525);
DISPLAY INVISIBLE (-6075 5525);
FORCEPROP 1 LAST PATH I778
J 2
(-5748 5650);
DISPLAY 0.872340 (-5748 5650);
PAINT GREEN (-5748 5650);
DISPLAY INVISIBLE (-5748 5650);
FORCEADD TAP..1
R 2
(-5750 5750);
FORCEPROP 3 LASTPIN (-5700 5750) SIG_NAME M_A_CPU0_SA_DQS_DN<3>
J 0
(-5690 5760);
DISPLAY 0.659574 (-5690 5760);
PAINT MONO (-5690 5760);
DISPLAY INVISIBLE (-5690 5760);
FORCEPROP 1 LASTPIN (-5700 5750) BN 3
J 2
(-5688 5758);
DISPLAY 0.489362 (-5688 5758);
PAINT MONO (-5688 5758);
FORCEPROP 2 LAST CDS_LIB mstr_standard
J 0
(-5750 5750);
DISPLAY INVISIBLE (-5750 5750);
FORCEPROP 1 LAST BODY_TYPE PLUMBING
J 2
(-5750 5800);
DISPLAY 0.872340 (-5750 5800);
PAINT GREEN (-5750 5800);
DISPLAY INVISIBLE (-5750 5800);
FORCEPROP 1 LAST HDL_TAP TRUE
J 2
(-6075 5625);
DISPLAY 0.872340 (-6075 5625);
DISPLAY INVISIBLE (-6075 5625);
FORCEPROP 1 LAST PATH I779
J 2
(-5748 5750);
DISPLAY 0.872340 (-5748 5750);
PAINT GREEN (-5748 5750);
DISPLAY INVISIBLE (-5748 5750);
FORCEADD TAP..1
R 2
(-5750 5850);
FORCEPROP 3 LASTPIN (-5700 5850) SIG_NAME M_A_CPU0_SA_DQS_DN<2>
J 0
(-5690 5860);
DISPLAY 0.659574 (-5690 5860);
PAINT MONO (-5690 5860);
DISPLAY INVISIBLE (-5690 5860);
FORCEPROP 1 LASTPIN (-5700 5850) BN 2
J 2
(-5688 5858);
DISPLAY 0.489362 (-5688 5858);
PAINT MONO (-5688 5858);
FORCEPROP 2 LAST CDS_LIB mstr_standard
J 0
(-5750 5850);
DISPLAY INVISIBLE (-5750 5850);
FORCEPROP 1 LAST BODY_TYPE PLUMBING
J 2
(-5750 5900);
DISPLAY 0.872340 (-5750 5900);
PAINT GREEN (-5750 5900);
DISPLAY INVISIBLE (-5750 5900);
FORCEPROP 1 LAST HDL_TAP TRUE
J 2
(-6075 5725);
DISPLAY 0.872340 (-6075 5725);
DISPLAY INVISIBLE (-6075 5725);
FORCEPROP 1 LAST PATH I780
J 2
(-5748 5850);
DISPLAY 0.872340 (-5748 5850);
PAINT GREEN (-5748 5850);
DISPLAY INVISIBLE (-5748 5850);
FORCEADD TAP..1
R 2
(-5750 5450);
FORCEPROP 3 LASTPIN (-5700 5450) SIG_NAME M_A_CPU0_SA_DQS_DN<6>
J 0
(-5690 5460);
DISPLAY 0.659574 (-5690 5460);
PAINT MONO (-5690 5460);
DISPLAY INVISIBLE (-5690 5460);
FORCEPROP 1 LASTPIN (-5700 5450) BN 6
J 2
(-5688 5458);
DISPLAY 0.489362 (-5688 5458);
PAINT MONO (-5688 5458);
FORCEPROP 2 LAST CDS_LIB mstr_standard
J 0
(-5750 5450);
DISPLAY INVISIBLE (-5750 5450);
FORCEPROP 1 LAST BODY_TYPE PLUMBING
J 2
(-5750 5500);
DISPLAY 0.872340 (-5750 5500);
PAINT GREEN (-5750 5500);
DISPLAY INVISIBLE (-5750 5500);
FORCEPROP 1 LAST HDL_TAP TRUE
J 2
(-6075 5325);
DISPLAY 0.872340 (-6075 5325);
DISPLAY INVISIBLE (-6075 5325);
FORCEPROP 1 LAST PATH I781
J 2
(-5748 5450);
DISPLAY 0.872340 (-5748 5450);
PAINT GREEN (-5748 5450);
DISPLAY INVISIBLE (-5748 5450);
FORCEADD TAP..1
R 2
(-5750 5550);
FORCEPROP 3 LASTPIN (-5700 5550) SIG_NAME M_A_CPU0_SA_DQS_DN<5>
J 0
(-5690 5560);
DISPLAY 0.659574 (-5690 5560);
PAINT MONO (-5690 5560);
DISPLAY INVISIBLE (-5690 5560);
FORCEPROP 1 LASTPIN (-5700 5550) BN 5
J 2
(-5688 5558);
DISPLAY 0.489362 (-5688 5558);
PAINT MONO (-5688 5558);
FORCEPROP 2 LAST CDS_LIB mstr_standard
J 0
(-5750 5550);
DISPLAY INVISIBLE (-5750 5550);
FORCEPROP 1 LAST BODY_TYPE PLUMBING
J 2
(-5750 5600);
DISPLAY 0.872340 (-5750 5600);
PAINT GREEN (-5750 5600);
DISPLAY INVISIBLE (-5750 5600);
FORCEPROP 1 LAST HDL_TAP TRUE
J 2
(-6075 5425);
DISPLAY 0.872340 (-6075 5425);
DISPLAY INVISIBLE (-6075 5425);
FORCEPROP 1 LAST PATH I782
J 2
(-5748 5550);
DISPLAY 0.872340 (-5748 5550);
PAINT GREEN (-5748 5550);
DISPLAY INVISIBLE (-5748 5550);
FORCEADD TAP..1
R 2
(-5750 5150);
FORCEPROP 3 LASTPIN (-5700 5150) SIG_NAME M_A_CPU0_SA_DQS_DN<9>
J 0
(-5690 5160);
DISPLAY 0.659574 (-5690 5160);
PAINT MONO (-5690 5160);
DISPLAY INVISIBLE (-5690 5160);
FORCEPROP 1 LASTPIN (-5700 5150) BN 9
J 2
(-5688 5158);
DISPLAY 0.489362 (-5688 5158);
PAINT MONO (-5688 5158);
FORCEPROP 2 LAST CDS_LIB mstr_standard
J 0
(-5750 5150);
DISPLAY INVISIBLE (-5750 5150);
FORCEPROP 1 LAST BODY_TYPE PLUMBING
J 2
(-5750 5200);
DISPLAY 0.872340 (-5750 5200);
PAINT GREEN (-5750 5200);
DISPLAY INVISIBLE (-5750 5200);
FORCEPROP 1 LAST HDL_TAP TRUE
J 2
(-6075 5025);
DISPLAY 0.872340 (-6075 5025);
DISPLAY INVISIBLE (-6075 5025);
FORCEPROP 1 LAST PATH I783
J 2
(-5748 5150);
DISPLAY 0.872340 (-5748 5150);
PAINT GREEN (-5748 5150);
DISPLAY INVISIBLE (-5748 5150);
FORCEADD TAP..1
R 2
(-5750 5250);
FORCEPROP 3 LASTPIN (-5700 5250) SIG_NAME M_A_CPU0_SA_DQS_DN<8>
J 0
(-5690 5260);
DISPLAY 0.659574 (-5690 5260);
PAINT MONO (-5690 5260);
DISPLAY INVISIBLE (-5690 5260);
FORCEPROP 1 LASTPIN (-5700 5250) BN 8
J 2
(-5688 5258);
DISPLAY 0.489362 (-5688 5258);
PAINT MONO (-5688 5258);
FORCEPROP 2 LAST CDS_LIB mstr_standard
J 0
(-5750 5250);
DISPLAY INVISIBLE (-5750 5250);
FORCEPROP 1 LAST BODY_TYPE PLUMBING
J 2
(-5750 5300);
DISPLAY 0.872340 (-5750 5300);
PAINT GREEN (-5750 5300);
DISPLAY INVISIBLE (-5750 5300);
FORCEPROP 1 LAST HDL_TAP TRUE
J 2
(-6075 5125);
DISPLAY 0.872340 (-6075 5125);
DISPLAY INVISIBLE (-6075 5125);
FORCEPROP 1 LAST PATH I784
J 2
(-5748 5250);
DISPLAY 0.872340 (-5748 5250);
PAINT GREEN (-5748 5250);
DISPLAY INVISIBLE (-5748 5250);
FORCEADD TAP..1
R 2
(-5750 5350);
FORCEPROP 3 LASTPIN (-5700 5350) SIG_NAME M_A_CPU0_SA_DQS_DN<7>
J 0
(-5690 5360);
DISPLAY 0.659574 (-5690 5360);
PAINT MONO (-5690 5360);
DISPLAY INVISIBLE (-5690 5360);
FORCEPROP 1 LASTPIN (-5700 5350) BN 7
J 2
(-5688 5358);
DISPLAY 0.489362 (-5688 5358);
PAINT MONO (-5688 5358);
FORCEPROP 2 LAST CDS_LIB mstr_standard
J 0
(-5750 5350);
DISPLAY INVISIBLE (-5750 5350);
FORCEPROP 1 LAST BODY_TYPE PLUMBING
J 2
(-5750 5400);
DISPLAY 0.872340 (-5750 5400);
PAINT GREEN (-5750 5400);
DISPLAY INVISIBLE (-5750 5400);
FORCEPROP 1 LAST HDL_TAP TRUE
J 2
(-6075 5225);
DISPLAY 0.872340 (-6075 5225);
DISPLAY INVISIBLE (-6075 5225);
FORCEPROP 1 LAST PATH I785
J 2
(-5748 5350);
DISPLAY 0.872340 (-5748 5350);
PAINT GREEN (-5748 5350);
DISPLAY INVISIBLE (-5748 5350);
FORCEADD TAP..1
R 2
(-5550 5050);
FORCEPROP 3 LASTPIN (-5500 5050) SIG_NAME M_A_CPU0_SB_DQS_DP<0>
J 0
(-5490 5060);
DISPLAY 0.659574 (-5490 5060);
PAINT MONO (-5490 5060);
DISPLAY INVISIBLE (-5490 5060);
FORCEPROP 1 LASTPIN (-5500 5050) BN 0
J 2
(-5488 5058);
DISPLAY 0.489362 (-5488 5058);
PAINT MONO (-5488 5058);
FORCEPROP 2 LAST CDS_LIB mstr_standard
J 0
(-5550 5050);
DISPLAY INVISIBLE (-5550 5050);
FORCEPROP 1 LAST BODY_TYPE PLUMBING
J 2
(-5550 5100);
DISPLAY 0.872340 (-5550 5100);
PAINT GREEN (-5550 5100);
DISPLAY INVISIBLE (-5550 5100);
FORCEPROP 1 LAST HDL_TAP TRUE
J 2
(-5875 4925);
DISPLAY 0.872340 (-5875 4925);
DISPLAY INVISIBLE (-5875 4925);
FORCEPROP 1 LAST PATH I786
J 2
(-5548 5050);
DISPLAY 0.872340 (-5548 5050);
PAINT GREEN (-5548 5050);
DISPLAY INVISIBLE (-5548 5050);
FORCEADD TAP..1
R 2
(-5550 4950);
FORCEPROP 3 LASTPIN (-5500 4950) SIG_NAME M_A_CPU0_SB_DQS_DP<1>
J 0
(-5490 4960);
DISPLAY 0.659574 (-5490 4960);
PAINT MONO (-5490 4960);
DISPLAY INVISIBLE (-5490 4960);
FORCEPROP 1 LASTPIN (-5500 4950) BN 1
J 2
(-5488 4958);
DISPLAY 0.489362 (-5488 4958);
PAINT MONO (-5488 4958);
FORCEPROP 2 LAST CDS_LIB mstr_standard
J 0
(-5550 4950);
DISPLAY INVISIBLE (-5550 4950);
FORCEPROP 1 LAST BODY_TYPE PLUMBING
J 2
(-5550 5000);
DISPLAY 0.872340 (-5550 5000);
PAINT GREEN (-5550 5000);
DISPLAY INVISIBLE (-5550 5000);
FORCEPROP 1 LAST HDL_TAP TRUE
J 2
(-5875 4825);
DISPLAY 0.872340 (-5875 4825);
DISPLAY INVISIBLE (-5875 4825);
FORCEPROP 1 LAST PATH I787
J 2
(-5548 4950);
DISPLAY 0.872340 (-5548 4950);
PAINT GREEN (-5548 4950);
DISPLAY INVISIBLE (-5548 4950);
FORCEADD TAP..1
R 2
(-5550 4750);
FORCEPROP 3 LASTPIN (-5500 4750) SIG_NAME M_A_CPU0_SB_DQS_DP<3>
J 0
(-5490 4760);
DISPLAY 0.659574 (-5490 4760);
PAINT MONO (-5490 4760);
DISPLAY INVISIBLE (-5490 4760);
FORCEPROP 1 LASTPIN (-5500 4750) BN 3
J 2
(-5488 4758);
DISPLAY 0.489362 (-5488 4758);
PAINT MONO (-5488 4758);
FORCEPROP 2 LAST CDS_LIB mstr_standard
J 0
(-5550 4750);
DISPLAY INVISIBLE (-5550 4750);
FORCEPROP 1 LAST BODY_TYPE PLUMBING
J 2
(-5550 4800);
DISPLAY 0.872340 (-5550 4800);
PAINT GREEN (-5550 4800);
DISPLAY INVISIBLE (-5550 4800);
FORCEPROP 1 LAST HDL_TAP TRUE
J 2
(-5875 4625);
DISPLAY 0.872340 (-5875 4625);
DISPLAY INVISIBLE (-5875 4625);
FORCEPROP 1 LAST PATH I788
J 2
(-5548 4750);
DISPLAY 0.872340 (-5548 4750);
PAINT GREEN (-5548 4750);
DISPLAY INVISIBLE (-5548 4750);
FORCEADD TAP..1
R 2
(-5550 4850);
FORCEPROP 3 LASTPIN (-5500 4850) SIG_NAME M_A_CPU0_SB_DQS_DP<2>
J 0
(-5490 4860);
DISPLAY 0.659574 (-5490 4860);
PAINT MONO (-5490 4860);
DISPLAY INVISIBLE (-5490 4860);
FORCEPROP 1 LASTPIN (-5500 4850) BN 2
J 2
(-5488 4858);
DISPLAY 0.489362 (-5488 4858);
PAINT MONO (-5488 4858);
FORCEPROP 2 LAST CDS_LIB mstr_standard
J 0
(-5550 4850);
DISPLAY INVISIBLE (-5550 4850);
FORCEPROP 1 LAST BODY_TYPE PLUMBING
J 2
(-5550 4900);
DISPLAY 0.872340 (-5550 4900);
PAINT GREEN (-5550 4900);
DISPLAY INVISIBLE (-5550 4900);
FORCEPROP 1 LAST HDL_TAP TRUE
J 2
(-5875 4725);
DISPLAY 0.872340 (-5875 4725);
DISPLAY INVISIBLE (-5875 4725);
FORCEPROP 1 LAST PATH I789
J 2
(-5548 4850);
DISPLAY 0.872340 (-5548 4850);
PAINT GREEN (-5548 4850);
DISPLAY INVISIBLE (-5548 4850);
FORCEADD TAP..1
R 2
(-5550 4650);
FORCEPROP 3 LASTPIN (-5500 4650) SIG_NAME M_A_CPU0_SB_DQS_DP<4>
J 0
(-5490 4660);
DISPLAY 0.659574 (-5490 4660);
PAINT MONO (-5490 4660);
DISPLAY INVISIBLE (-5490 4660);
FORCEPROP 1 LASTPIN (-5500 4650) BN 4
J 2
(-5488 4658);
DISPLAY 0.489362 (-5488 4658);
PAINT MONO (-5488 4658);
FORCEPROP 2 LAST CDS_LIB mstr_standard
J 0
(-5550 4650);
DISPLAY INVISIBLE (-5550 4650);
FORCEPROP 1 LAST BODY_TYPE PLUMBING
J 2
(-5550 4700);
DISPLAY 0.872340 (-5550 4700);
PAINT GREEN (-5550 4700);
DISPLAY INVISIBLE (-5550 4700);
FORCEPROP 1 LAST HDL_TAP TRUE
J 2
(-5875 4525);
DISPLAY 0.872340 (-5875 4525);
DISPLAY INVISIBLE (-5875 4525);
FORCEPROP 1 LAST PATH I790
J 2
(-5548 4650);
DISPLAY 0.872340 (-5548 4650);
PAINT GREEN (-5548 4650);
DISPLAY INVISIBLE (-5548 4650);
FORCEADD TAP..1
R 2
(-5550 4550);
FORCEPROP 3 LASTPIN (-5500 4550) SIG_NAME M_A_CPU0_SB_DQS_DP<5>
J 0
(-5490 4560);
DISPLAY 0.659574 (-5490 4560);
PAINT MONO (-5490 4560);
DISPLAY INVISIBLE (-5490 4560);
FORCEPROP 1 LASTPIN (-5500 4550) BN 5
J 2
(-5488 4558);
DISPLAY 0.489362 (-5488 4558);
PAINT MONO (-5488 4558);
FORCEPROP 2 LAST CDS_LIB mstr_standard
J 0
(-5550 4550);
DISPLAY INVISIBLE (-5550 4550);
FORCEPROP 1 LAST BODY_TYPE PLUMBING
J 2
(-5550 4600);
DISPLAY 0.872340 (-5550 4600);
PAINT GREEN (-5550 4600);
DISPLAY INVISIBLE (-5550 4600);
FORCEPROP 1 LAST HDL_TAP TRUE
J 2
(-5875 4425);
DISPLAY 0.872340 (-5875 4425);
DISPLAY INVISIBLE (-5875 4425);
FORCEPROP 1 LAST PATH I791
J 2
(-5548 4550);
DISPLAY 0.872340 (-5548 4550);
PAINT GREEN (-5548 4550);
DISPLAY INVISIBLE (-5548 4550);
FORCEADD TAP..1
R 2
(-5550 4450);
FORCEPROP 3 LASTPIN (-5500 4450) SIG_NAME M_A_CPU0_SB_DQS_DP<6>
J 0
(-5490 4460);
DISPLAY 0.659574 (-5490 4460);
PAINT MONO (-5490 4460);
DISPLAY INVISIBLE (-5490 4460);
FORCEPROP 1 LASTPIN (-5500 4450) BN 6
J 2
(-5488 4458);
DISPLAY 0.489362 (-5488 4458);
PAINT MONO (-5488 4458);
FORCEPROP 2 LAST CDS_LIB mstr_standard
J 0
(-5550 4450);
DISPLAY INVISIBLE (-5550 4450);
FORCEPROP 1 LAST BODY_TYPE PLUMBING
J 2
(-5550 4500);
DISPLAY 0.872340 (-5550 4500);
PAINT GREEN (-5550 4500);
DISPLAY INVISIBLE (-5550 4500);
FORCEPROP 1 LAST HDL_TAP TRUE
J 2
(-5875 4325);
DISPLAY 0.872340 (-5875 4325);
DISPLAY INVISIBLE (-5875 4325);
FORCEPROP 1 LAST PATH I792
J 2
(-5548 4450);
DISPLAY 0.872340 (-5548 4450);
PAINT GREEN (-5548 4450);
DISPLAY INVISIBLE (-5548 4450);
FORCEADD TAP..1
R 2
(-5550 4350);
FORCEPROP 3 LASTPIN (-5500 4350) SIG_NAME M_A_CPU0_SB_DQS_DP<7>
J 0
(-5490 4360);
DISPLAY 0.659574 (-5490 4360);
PAINT MONO (-5490 4360);
DISPLAY INVISIBLE (-5490 4360);
FORCEPROP 1 LASTPIN (-5500 4350) BN 7
J 2
(-5488 4358);
DISPLAY 0.489362 (-5488 4358);
PAINT MONO (-5488 4358);
FORCEPROP 2 LAST CDS_LIB mstr_standard
J 0
(-5550 4350);
DISPLAY INVISIBLE (-5550 4350);
FORCEPROP 1 LAST BODY_TYPE PLUMBING
J 2
(-5550 4400);
DISPLAY 0.872340 (-5550 4400);
PAINT GREEN (-5550 4400);
DISPLAY INVISIBLE (-5550 4400);
FORCEPROP 1 LAST HDL_TAP TRUE
J 2
(-5875 4225);
DISPLAY 0.872340 (-5875 4225);
DISPLAY INVISIBLE (-5875 4225);
FORCEPROP 1 LAST PATH I793
J 2
(-5548 4350);
DISPLAY 0.872340 (-5548 4350);
PAINT GREEN (-5548 4350);
DISPLAY INVISIBLE (-5548 4350);
FORCEADD TAP..1
R 2
(-5550 4250);
FORCEPROP 3 LASTPIN (-5500 4250) SIG_NAME M_A_CPU0_SB_DQS_DP<8>
J 0
(-5490 4260);
DISPLAY 0.659574 (-5490 4260);
PAINT MONO (-5490 4260);
DISPLAY INVISIBLE (-5490 4260);
FORCEPROP 1 LASTPIN (-5500 4250) BN 8
J 2
(-5488 4258);
DISPLAY 0.489362 (-5488 4258);
PAINT MONO (-5488 4258);
FORCEPROP 2 LAST CDS_LIB mstr_standard
J 0
(-5550 4250);
DISPLAY INVISIBLE (-5550 4250);
FORCEPROP 1 LAST BODY_TYPE PLUMBING
J 2
(-5550 4300);
DISPLAY 0.872340 (-5550 4300);
PAINT GREEN (-5550 4300);
DISPLAY INVISIBLE (-5550 4300);
FORCEPROP 1 LAST HDL_TAP TRUE
J 2
(-5875 4125);
DISPLAY 0.872340 (-5875 4125);
DISPLAY INVISIBLE (-5875 4125);
FORCEPROP 1 LAST PATH I794
J 2
(-5548 4250);
DISPLAY 0.872340 (-5548 4250);
PAINT GREEN (-5548 4250);
DISPLAY INVISIBLE (-5548 4250);
FORCEADD TAP..1
R 2
(-5550 4150);
FORCEPROP 3 LASTPIN (-5500 4150) SIG_NAME M_A_CPU0_SB_DQS_DP<9>
J 0
(-5490 4160);
DISPLAY 0.659574 (-5490 4160);
PAINT MONO (-5490 4160);
DISPLAY INVISIBLE (-5490 4160);
FORCEPROP 1 LASTPIN (-5500 4150) BN 9
J 2
(-5488 4158);
DISPLAY 0.489362 (-5488 4158);
PAINT MONO (-5488 4158);
FORCEPROP 2 LAST CDS_LIB mstr_standard
J 0
(-5550 4150);
DISPLAY INVISIBLE (-5550 4150);
FORCEPROP 1 LAST BODY_TYPE PLUMBING
J 2
(-5550 4200);
DISPLAY 0.872340 (-5550 4200);
PAINT GREEN (-5550 4200);
DISPLAY INVISIBLE (-5550 4200);
FORCEPROP 1 LAST HDL_TAP TRUE
J 2
(-5875 4025);
DISPLAY 0.872340 (-5875 4025);
DISPLAY INVISIBLE (-5875 4025);
FORCEPROP 1 LAST PATH I795
J 2
(-5548 4150);
DISPLAY 0.872340 (-5548 4150);
PAINT GREEN (-5548 4150);
DISPLAY INVISIBLE (-5548 4150);
FORCEADD TAP..1
R 2
(-5750 4900);
FORCEPROP 3 LASTPIN (-5700 4900) SIG_NAME M_A_CPU0_SB_DQS_DN<1>
J 0
(-5690 4910);
DISPLAY 0.659574 (-5690 4910);
PAINT MONO (-5690 4910);
DISPLAY INVISIBLE (-5690 4910);
FORCEPROP 1 LASTPIN (-5700 4900) BN 1
J 2
(-5688 4908);
DISPLAY 0.489362 (-5688 4908);
PAINT MONO (-5688 4908);
FORCEPROP 2 LAST CDS_LIB mstr_standard
J 0
(-5750 4900);
DISPLAY INVISIBLE (-5750 4900);
FORCEPROP 1 LAST BODY_TYPE PLUMBING
J 2
(-5750 4950);
DISPLAY 0.872340 (-5750 4950);
PAINT GREEN (-5750 4950);
DISPLAY INVISIBLE (-5750 4950);
FORCEPROP 1 LAST HDL_TAP TRUE
J 2
(-6075 4775);
DISPLAY 0.872340 (-6075 4775);
DISPLAY INVISIBLE (-6075 4775);
FORCEPROP 1 LAST PATH I796
J 2
(-5748 4900);
DISPLAY 0.872340 (-5748 4900);
PAINT GREEN (-5748 4900);
DISPLAY INVISIBLE (-5748 4900);
FORCEADD TAP..1
R 2
(-5750 5000);
FORCEPROP 3 LASTPIN (-5700 5000) SIG_NAME M_A_CPU0_SB_DQS_DN<0>
J 0
(-5690 5010);
DISPLAY 0.659574 (-5690 5010);
PAINT MONO (-5690 5010);
DISPLAY INVISIBLE (-5690 5010);
FORCEPROP 1 LASTPIN (-5700 5000) BN 0
J 2
(-5688 5008);
DISPLAY 0.489362 (-5688 5008);
PAINT MONO (-5688 5008);
FORCEPROP 2 LAST CDS_LIB mstr_standard
J 0
(-5750 5000);
DISPLAY INVISIBLE (-5750 5000);
FORCEPROP 1 LAST BODY_TYPE PLUMBING
J 2
(-5750 5050);
DISPLAY 0.872340 (-5750 5050);
PAINT GREEN (-5750 5050);
DISPLAY INVISIBLE (-5750 5050);
FORCEPROP 1 LAST HDL_TAP TRUE
J 2
(-6075 4875);
DISPLAY 0.872340 (-6075 4875);
DISPLAY INVISIBLE (-6075 4875);
FORCEPROP 1 LAST PATH I797
J 2
(-5748 5000);
DISPLAY 0.872340 (-5748 5000);
PAINT GREEN (-5748 5000);
DISPLAY INVISIBLE (-5748 5000);
FORCEADD TAP..1
R 2
(-5750 4700);
FORCEPROP 3 LASTPIN (-5700 4700) SIG_NAME M_A_CPU0_SB_DQS_DN<3>
J 0
(-5690 4710);
DISPLAY 0.659574 (-5690 4710);
PAINT MONO (-5690 4710);
DISPLAY INVISIBLE (-5690 4710);
FORCEPROP 1 LASTPIN (-5700 4700) BN 3
J 2
(-5688 4708);
DISPLAY 0.489362 (-5688 4708);
PAINT MONO (-5688 4708);
FORCEPROP 2 LAST CDS_LIB mstr_standard
J 0
(-5750 4700);
DISPLAY INVISIBLE (-5750 4700);
FORCEPROP 1 LAST BODY_TYPE PLUMBING
J 2
(-5750 4750);
DISPLAY 0.872340 (-5750 4750);
PAINT GREEN (-5750 4750);
DISPLAY INVISIBLE (-5750 4750);
FORCEPROP 1 LAST HDL_TAP TRUE
J 2
(-6075 4575);
DISPLAY 0.872340 (-6075 4575);
DISPLAY INVISIBLE (-6075 4575);
FORCEPROP 1 LAST PATH I798
J 2
(-5748 4700);
DISPLAY 0.872340 (-5748 4700);
PAINT GREEN (-5748 4700);
DISPLAY INVISIBLE (-5748 4700);
FORCEADD TAP..1
R 2
(-5750 4800);
FORCEPROP 3 LASTPIN (-5700 4800) SIG_NAME M_A_CPU0_SB_DQS_DN<2>
J 0
(-5690 4810);
DISPLAY 0.659574 (-5690 4810);
PAINT MONO (-5690 4810);
DISPLAY INVISIBLE (-5690 4810);
FORCEPROP 1 LASTPIN (-5700 4800) BN 2
J 2
(-5688 4808);
DISPLAY 0.489362 (-5688 4808);
PAINT MONO (-5688 4808);
FORCEPROP 2 LAST CDS_LIB mstr_standard
J 0
(-5750 4800);
DISPLAY INVISIBLE (-5750 4800);
FORCEPROP 1 LAST BODY_TYPE PLUMBING
J 2
(-5750 4850);
DISPLAY 0.872340 (-5750 4850);
PAINT GREEN (-5750 4850);
DISPLAY INVISIBLE (-5750 4850);
FORCEPROP 1 LAST HDL_TAP TRUE
J 2
(-6075 4675);
DISPLAY 0.872340 (-6075 4675);
DISPLAY INVISIBLE (-6075 4675);
FORCEPROP 1 LAST PATH I799
J 2
(-5748 4800);
DISPLAY 0.872340 (-5748 4800);
PAINT GREEN (-5748 4800);
DISPLAY INVISIBLE (-5748 4800);
FORCEADD TAP..1
R 2
(-5750 4600);
FORCEPROP 3 LASTPIN (-5700 4600) SIG_NAME M_A_CPU0_SB_DQS_DN<4>
J 0
(-5690 4610);
DISPLAY 0.659574 (-5690 4610);
PAINT MONO (-5690 4610);
DISPLAY INVISIBLE (-5690 4610);
FORCEPROP 1 LASTPIN (-5700 4600) BN 4
J 2
(-5688 4608);
DISPLAY 0.489362 (-5688 4608);
PAINT MONO (-5688 4608);
FORCEPROP 2 LAST CDS_LIB mstr_standard
J 0
(-5750 4600);
DISPLAY INVISIBLE (-5750 4600);
FORCEPROP 1 LAST BODY_TYPE PLUMBING
J 2
(-5750 4650);
DISPLAY 0.872340 (-5750 4650);
PAINT GREEN (-5750 4650);
DISPLAY INVISIBLE (-5750 4650);
FORCEPROP 1 LAST HDL_TAP TRUE
J 2
(-6075 4475);
DISPLAY 0.872340 (-6075 4475);
DISPLAY INVISIBLE (-6075 4475);
FORCEPROP 1 LAST PATH I800
J 2
(-5748 4600);
DISPLAY 0.872340 (-5748 4600);
PAINT GREEN (-5748 4600);
DISPLAY INVISIBLE (-5748 4600);
FORCEADD TAP..1
R 2
(-5750 4400);
FORCEPROP 3 LASTPIN (-5700 4400) SIG_NAME M_A_CPU0_SB_DQS_DN<6>
J 0
(-5690 4410);
DISPLAY 0.659574 (-5690 4410);
PAINT MONO (-5690 4410);
DISPLAY INVISIBLE (-5690 4410);
FORCEPROP 1 LASTPIN (-5700 4400) BN 6
J 2
(-5688 4408);
DISPLAY 0.489362 (-5688 4408);
PAINT MONO (-5688 4408);
FORCEPROP 2 LAST CDS_LIB mstr_standard
J 0
(-5750 4400);
DISPLAY INVISIBLE (-5750 4400);
FORCEPROP 1 LAST BODY_TYPE PLUMBING
J 2
(-5750 4450);
DISPLAY 0.872340 (-5750 4450);
PAINT GREEN (-5750 4450);
DISPLAY INVISIBLE (-5750 4450);
FORCEPROP 1 LAST HDL_TAP TRUE
J 2
(-6075 4275);
DISPLAY 0.872340 (-6075 4275);
DISPLAY INVISIBLE (-6075 4275);
FORCEPROP 1 LAST PATH I801
J 2
(-5748 4400);
DISPLAY 0.872340 (-5748 4400);
PAINT GREEN (-5748 4400);
DISPLAY INVISIBLE (-5748 4400);
FORCEADD TAP..1
R 2
(-5750 4500);
FORCEPROP 3 LASTPIN (-5700 4500) SIG_NAME M_A_CPU0_SB_DQS_DN<5>
J 0
(-5690 4510);
DISPLAY 0.659574 (-5690 4510);
PAINT MONO (-5690 4510);
DISPLAY INVISIBLE (-5690 4510);
FORCEPROP 1 LASTPIN (-5700 4500) BN 5
J 2
(-5688 4508);
DISPLAY 0.489362 (-5688 4508);
PAINT MONO (-5688 4508);
FORCEPROP 2 LAST CDS_LIB mstr_standard
J 0
(-5750 4500);
DISPLAY INVISIBLE (-5750 4500);
FORCEPROP 1 LAST BODY_TYPE PLUMBING
J 2
(-5750 4550);
DISPLAY 0.872340 (-5750 4550);
PAINT GREEN (-5750 4550);
DISPLAY INVISIBLE (-5750 4550);
FORCEPROP 1 LAST HDL_TAP TRUE
J 2
(-6075 4375);
DISPLAY 0.872340 (-6075 4375);
DISPLAY INVISIBLE (-6075 4375);
FORCEPROP 1 LAST PATH I802
J 2
(-5748 4500);
DISPLAY 0.872340 (-5748 4500);
PAINT GREEN (-5748 4500);
DISPLAY INVISIBLE (-5748 4500);
FORCEADD TAP..1
R 2
(-5750 4100);
FORCEPROP 3 LASTPIN (-5700 4100) SIG_NAME M_A_CPU0_SB_DQS_DN<9>
J 0
(-5690 4110);
DISPLAY 0.659574 (-5690 4110);
PAINT MONO (-5690 4110);
DISPLAY INVISIBLE (-5690 4110);
FORCEPROP 1 LASTPIN (-5700 4100) BN 9
J 2
(-5688 4108);
DISPLAY 0.489362 (-5688 4108);
PAINT MONO (-5688 4108);
FORCEPROP 2 LAST CDS_LIB mstr_standard
J 0
(-5750 4100);
DISPLAY INVISIBLE (-5750 4100);
FORCEPROP 1 LAST BODY_TYPE PLUMBING
J 2
(-5750 4150);
DISPLAY 0.872340 (-5750 4150);
PAINT GREEN (-5750 4150);
DISPLAY INVISIBLE (-5750 4150);
FORCEPROP 1 LAST HDL_TAP TRUE
J 2
(-6075 3975);
DISPLAY 0.872340 (-6075 3975);
DISPLAY INVISIBLE (-6075 3975);
FORCEPROP 1 LAST PATH I803
J 2
(-5748 4100);
DISPLAY 0.872340 (-5748 4100);
PAINT GREEN (-5748 4100);
DISPLAY INVISIBLE (-5748 4100);
FORCEADD TAP..1
R 2
(-5750 4200);
FORCEPROP 3 LASTPIN (-5700 4200) SIG_NAME M_A_CPU0_SB_DQS_DN<8>
J 0
(-5690 4210);
DISPLAY 0.659574 (-5690 4210);
PAINT MONO (-5690 4210);
DISPLAY INVISIBLE (-5690 4210);
FORCEPROP 1 LASTPIN (-5700 4200) BN 8
J 2
(-5688 4208);
DISPLAY 0.489362 (-5688 4208);
PAINT MONO (-5688 4208);
FORCEPROP 2 LAST CDS_LIB mstr_standard
J 0
(-5750 4200);
DISPLAY INVISIBLE (-5750 4200);
FORCEPROP 1 LAST BODY_TYPE PLUMBING
J 2
(-5750 4250);
DISPLAY 0.872340 (-5750 4250);
PAINT GREEN (-5750 4250);
DISPLAY INVISIBLE (-5750 4250);
FORCEPROP 1 LAST HDL_TAP TRUE
J 2
(-6075 4075);
DISPLAY 0.872340 (-6075 4075);
DISPLAY INVISIBLE (-6075 4075);
FORCEPROP 1 LAST PATH I804
J 2
(-5748 4200);
DISPLAY 0.872340 (-5748 4200);
PAINT GREEN (-5748 4200);
DISPLAY INVISIBLE (-5748 4200);
FORCEADD TAP..1
R 2
(-5750 4300);
FORCEPROP 3 LASTPIN (-5700 4300) SIG_NAME M_A_CPU0_SB_DQS_DN<7>
J 0
(-5690 4310);
DISPLAY 0.659574 (-5690 4310);
PAINT MONO (-5690 4310);
DISPLAY INVISIBLE (-5690 4310);
FORCEPROP 1 LASTPIN (-5700 4300) BN 7
J 2
(-5688 4308);
DISPLAY 0.489362 (-5688 4308);
PAINT MONO (-5688 4308);
FORCEPROP 2 LAST CDS_LIB mstr_standard
J 0
(-5750 4300);
DISPLAY INVISIBLE (-5750 4300);
FORCEPROP 1 LAST BODY_TYPE PLUMBING
J 2
(-5750 4350);
DISPLAY 0.872340 (-5750 4350);
PAINT GREEN (-5750 4350);
DISPLAY INVISIBLE (-5750 4350);
FORCEPROP 1 LAST HDL_TAP TRUE
J 2
(-6075 4175);
DISPLAY 0.872340 (-6075 4175);
DISPLAY INVISIBLE (-6075 4175);
FORCEPROP 1 LAST PATH I805
J 2
(-5748 4300);
DISPLAY 0.872340 (-5748 4300);
PAINT GREEN (-5748 4300);
DISPLAY INVISIBLE (-5748 4300);
FORCEADD OFFPAGE..3
R 2
(-6450 6075);
FORCEPROP 2 LAST $XR0 85 
J 0
(-6729 6075);
DISPLAY 0.638298 (-6729 6075);
PAINT MONO (-6729 6075);
FORCEPROP 2 LAST PATH I806
J 0
(-6750 6125);
DISPLAY 1.021277 (-6750 6125);
DISPLAY INVISIBLE (-6750 6125);
FORCEPROP 1 LAST COMMENT_BODY TRUE
J 2
(-6400 5975);
DISPLAY 0.872340 (-6400 5975);
PAINT GREEN (-6400 5975);
DISPLAY INVISIBLE (-6400 5975);
FORCEPROP 1 LAST OFFPAGE TRUE
J 2
(-6775 5950);
DISPLAY 0.872340 (-6775 5950);
PAINT GREEN (-6775 5950);
DISPLAY INVISIBLE (-6775 5950);
FORCEPROP 2 LAST CDS_LIB standard
J 0
(-6450 6075);
DISPLAY INVISIBLE (-6450 6075);
FORCEADD OFFPAGE..3
R 2
(-6450 6125);
FORCEPROP 2 LAST $XR0 85 
J 0
(-6729 6125);
DISPLAY 0.638298 (-6729 6125);
PAINT MONO (-6729 6125);
FORCEPROP 2 LAST PATH I807
J 0
(-6750 6175);
DISPLAY 1.021277 (-6750 6175);
DISPLAY INVISIBLE (-6750 6175);
FORCEPROP 1 LAST COMMENT_BODY TRUE
J 2
(-6400 6025);
DISPLAY 0.872340 (-6400 6025);
PAINT GREEN (-6400 6025);
DISPLAY INVISIBLE (-6400 6025);
FORCEPROP 1 LAST OFFPAGE TRUE
J 2
(-6775 6000);
DISPLAY 0.872340 (-6775 6000);
PAINT GREEN (-6775 6000);
DISPLAY INVISIBLE (-6775 6000);
FORCEPROP 2 LAST CDS_LIB standard
J 0
(-6450 6125);
DISPLAY INVISIBLE (-6450 6125);
FORCEADD OFFPAGE..3
R 2
(-6450 5025);
FORCEPROP 2 LASTPIN (-6400 5025) SIG_NAME M_A_CPU0_SB_DQS_DN<9:0>
J 0
(-6435 5035);
DISPLAY 0.489362 (-6435 5035);
FORCEPROP 2 LAST $XR0 85 
J 0
(-6729 5025);
DISPLAY 0.638298 (-6729 5025);
PAINT MONO (-6729 5025);
FORCEPROP 2 LAST PATH I808
J 0
(-6750 5075);
DISPLAY 1.021277 (-6750 5075);
DISPLAY INVISIBLE (-6750 5075);
FORCEPROP 1 LAST COMMENT_BODY TRUE
J 2
(-6400 4925);
DISPLAY 0.872340 (-6400 4925);
PAINT GREEN (-6400 4925);
DISPLAY INVISIBLE (-6400 4925);
FORCEPROP 1 LAST OFFPAGE TRUE
J 2
(-6775 4900);
DISPLAY 0.872340 (-6775 4900);
PAINT GREEN (-6775 4900);
DISPLAY INVISIBLE (-6775 4900);
FORCEPROP 2 LAST CDS_LIB standard
J 0
(-6450 5025);
DISPLAY INVISIBLE (-6450 5025);
FORCEADD OFFPAGE..3
R 2
(-6450 5075);
FORCEPROP 2 LAST $XR0 85 
J 0
(-6729 5075);
DISPLAY 0.638298 (-6729 5075);
PAINT MONO (-6729 5075);
FORCEPROP 2 LAST PATH I809
J 0
(-6750 5125);
DISPLAY 1.021277 (-6750 5125);
DISPLAY INVISIBLE (-6750 5125);
FORCEPROP 1 LAST COMMENT_BODY TRUE
J 2
(-6400 4975);
DISPLAY 0.872340 (-6400 4975);
PAINT GREEN (-6400 4975);
DISPLAY INVISIBLE (-6400 4975);
FORCEPROP 1 LAST OFFPAGE TRUE
J 2
(-6775 4950);
DISPLAY 0.872340 (-6775 4950);
PAINT GREEN (-6775 4950);
DISPLAY INVISIBLE (-6775 4950);
FORCEPROP 2 LAST CDS_LIB standard
J 0
(-6450 5075);
DISPLAY INVISIBLE (-6450 5075);
FORCEADD TAP..1
R 2
(-5700 3900);
FORCEPROP 3 LASTPIN (-5650 3900) SIG_NAME M_A_CPU0_SA_CA<1>
J 0
(-5640 3910);
DISPLAY 0.659574 (-5640 3910);
PAINT MONO (-5640 3910);
DISPLAY INVISIBLE (-5640 3910);
FORCEPROP 1 LASTPIN (-5650 3900) BN 1
J 2
(-5638 3908);
DISPLAY 0.489362 (-5638 3908);
PAINT MONO (-5638 3908);
FORCEPROP 2 LAST CDS_LIB mstr_standard
J 0
(-5700 3900);
DISPLAY INVISIBLE (-5700 3900);
FORCEPROP 1 LAST BODY_TYPE PLUMBING
J 2
(-5700 3950);
DISPLAY 0.872340 (-5700 3950);
PAINT GREEN (-5700 3950);
DISPLAY INVISIBLE (-5700 3950);
FORCEPROP 1 LAST HDL_TAP TRUE
J 2
(-6025 3775);
DISPLAY 0.872340 (-6025 3775);
DISPLAY INVISIBLE (-6025 3775);
FORCEPROP 1 LAST PATH I810
J 2
(-5698 3900);
DISPLAY 0.872340 (-5698 3900);
PAINT GREEN (-5698 3900);
DISPLAY INVISIBLE (-5698 3900);
FORCEADD TAP..1
R 2
(-5700 3950);
FORCEPROP 3 LASTPIN (-5650 3950) SIG_NAME M_A_CPU0_SA_CA<0>
J 0
(-5640 3960);
DISPLAY 0.659574 (-5640 3960);
PAINT MONO (-5640 3960);
DISPLAY INVISIBLE (-5640 3960);
FORCEPROP 1 LASTPIN (-5650 3950) BN 0
J 2
(-5638 3958);
DISPLAY 0.489362 (-5638 3958);
PAINT MONO (-5638 3958);
FORCEPROP 2 LAST CDS_LIB mstr_standard
J 0
(-5700 3950);
DISPLAY INVISIBLE (-5700 3950);
FORCEPROP 1 LAST BODY_TYPE PLUMBING
J 2
(-5700 4000);
DISPLAY 0.872340 (-5700 4000);
PAINT GREEN (-5700 4000);
DISPLAY INVISIBLE (-5700 4000);
FORCEPROP 1 LAST HDL_TAP TRUE
J 2
(-6025 3825);
DISPLAY 0.872340 (-6025 3825);
DISPLAY INVISIBLE (-6025 3825);
FORCEPROP 1 LAST PATH I811
J 2
(-5698 3950);
DISPLAY 0.872340 (-5698 3950);
PAINT GREEN (-5698 3950);
DISPLAY INVISIBLE (-5698 3950);
FORCEADD TAP..1
R 2
(-5700 3850);
FORCEPROP 3 LASTPIN (-5650 3850) SIG_NAME M_A_CPU0_SA_CA<2>
J 0
(-5640 3860);
DISPLAY 0.659574 (-5640 3860);
PAINT MONO (-5640 3860);
DISPLAY INVISIBLE (-5640 3860);
FORCEPROP 1 LASTPIN (-5650 3850) BN 2
J 2
(-5638 3858);
DISPLAY 0.489362 (-5638 3858);
PAINT MONO (-5638 3858);
FORCEPROP 2 LAST CDS_LIB mstr_standard
J 0
(-5700 3850);
DISPLAY INVISIBLE (-5700 3850);
FORCEPROP 1 LAST BODY_TYPE PLUMBING
J 2
(-5700 3900);
DISPLAY 0.872340 (-5700 3900);
PAINT GREEN (-5700 3900);
DISPLAY INVISIBLE (-5700 3900);
FORCEPROP 1 LAST HDL_TAP TRUE
J 2
(-6025 3725);
DISPLAY 0.872340 (-6025 3725);
DISPLAY INVISIBLE (-6025 3725);
FORCEPROP 1 LAST PATH I812
J 2
(-5698 3850);
DISPLAY 0.872340 (-5698 3850);
PAINT GREEN (-5698 3850);
DISPLAY INVISIBLE (-5698 3850);
FORCEADD TAP..1
R 2
(-5700 3750);
FORCEPROP 3 LASTPIN (-5650 3750) SIG_NAME M_A_CPU0_SA_CA<4>
J 0
(-5640 3760);
DISPLAY 0.659574 (-5640 3760);
PAINT MONO (-5640 3760);
DISPLAY INVISIBLE (-5640 3760);
FORCEPROP 1 LASTPIN (-5650 3750) BN 4
J 2
(-5638 3758);
DISPLAY 0.489362 (-5638 3758);
PAINT MONO (-5638 3758);
FORCEPROP 2 LAST CDS_LIB mstr_standard
J 0
(-5700 3750);
DISPLAY INVISIBLE (-5700 3750);
FORCEPROP 1 LAST BODY_TYPE PLUMBING
J 2
(-5700 3800);
DISPLAY 0.872340 (-5700 3800);
PAINT GREEN (-5700 3800);
DISPLAY INVISIBLE (-5700 3800);
FORCEPROP 1 LAST HDL_TAP TRUE
J 2
(-6025 3625);
DISPLAY 0.872340 (-6025 3625);
DISPLAY INVISIBLE (-6025 3625);
FORCEPROP 1 LAST PATH I813
J 2
(-5698 3750);
DISPLAY 0.872340 (-5698 3750);
PAINT GREEN (-5698 3750);
DISPLAY INVISIBLE (-5698 3750);
FORCEADD TAP..1
R 2
(-5700 3800);
FORCEPROP 3 LASTPIN (-5650 3800) SIG_NAME M_A_CPU0_SA_CA<3>
J 0
(-5640 3810);
DISPLAY 0.659574 (-5640 3810);
PAINT MONO (-5640 3810);
DISPLAY INVISIBLE (-5640 3810);
FORCEPROP 1 LASTPIN (-5650 3800) BN 3
J 2
(-5638 3808);
DISPLAY 0.489362 (-5638 3808);
PAINT MONO (-5638 3808);
FORCEPROP 2 LAST CDS_LIB mstr_standard
J 0
(-5700 3800);
DISPLAY INVISIBLE (-5700 3800);
FORCEPROP 1 LAST BODY_TYPE PLUMBING
J 2
(-5700 3850);
DISPLAY 0.872340 (-5700 3850);
PAINT GREEN (-5700 3850);
DISPLAY INVISIBLE (-5700 3850);
FORCEPROP 1 LAST HDL_TAP TRUE
J 2
(-6025 3675);
DISPLAY 0.872340 (-6025 3675);
DISPLAY INVISIBLE (-6025 3675);
FORCEPROP 1 LAST PATH I814
J 2
(-5698 3800);
DISPLAY 0.872340 (-5698 3800);
PAINT GREEN (-5698 3800);
DISPLAY INVISIBLE (-5698 3800);
FORCEADD TAP..1
R 2
(-5700 3650);
FORCEPROP 3 LASTPIN (-5650 3650) SIG_NAME M_A_CPU0_SA_CA<6>
J 0
(-5640 3660);
DISPLAY 0.659574 (-5640 3660);
PAINT MONO (-5640 3660);
DISPLAY INVISIBLE (-5640 3660);
FORCEPROP 1 LASTPIN (-5650 3650) BN 6
J 2
(-5638 3658);
DISPLAY 0.489362 (-5638 3658);
PAINT MONO (-5638 3658);
FORCEPROP 2 LAST CDS_LIB mstr_standard
J 0
(-5700 3650);
DISPLAY INVISIBLE (-5700 3650);
FORCEPROP 1 LAST BODY_TYPE PLUMBING
J 2
(-5700 3700);
DISPLAY 0.872340 (-5700 3700);
PAINT GREEN (-5700 3700);
DISPLAY INVISIBLE (-5700 3700);
FORCEPROP 1 LAST HDL_TAP TRUE
J 2
(-6025 3525);
DISPLAY 0.872340 (-6025 3525);
DISPLAY INVISIBLE (-6025 3525);
FORCEPROP 1 LAST PATH I815
J 2
(-5698 3650);
DISPLAY 0.872340 (-5698 3650);
PAINT GREEN (-5698 3650);
DISPLAY INVISIBLE (-5698 3650);
FORCEADD TAP..1
R 2
(-5700 3700);
FORCEPROP 3 LASTPIN (-5650 3700) SIG_NAME M_A_CPU0_SA_CA<5>
J 0
(-5640 3710);
DISPLAY 0.659574 (-5640 3710);
PAINT MONO (-5640 3710);
DISPLAY INVISIBLE (-5640 3710);
FORCEPROP 1 LASTPIN (-5650 3700) BN 5
J 2
(-5638 3708);
DISPLAY 0.489362 (-5638 3708);
PAINT MONO (-5638 3708);
FORCEPROP 2 LAST CDS_LIB mstr_standard
J 0
(-5700 3700);
DISPLAY INVISIBLE (-5700 3700);
FORCEPROP 1 LAST BODY_TYPE PLUMBING
J 2
(-5700 3750);
DISPLAY 0.872340 (-5700 3750);
PAINT GREEN (-5700 3750);
DISPLAY INVISIBLE (-5700 3750);
FORCEPROP 1 LAST HDL_TAP TRUE
J 2
(-6025 3575);
DISPLAY 0.872340 (-6025 3575);
DISPLAY INVISIBLE (-6025 3575);
FORCEPROP 1 LAST PATH I816
J 2
(-5698 3700);
DISPLAY 0.872340 (-5698 3700);
PAINT GREEN (-5698 3700);
DISPLAY INVISIBLE (-5698 3700);
FORCEADD TAP..1
R 2
(-5700 3500);
FORCEPROP 3 LASTPIN (-5650 3500) SIG_NAME M_A_CPU0_SB_CA<1>
J 0
(-5640 3510);
DISPLAY 0.659574 (-5640 3510);
PAINT MONO (-5640 3510);
DISPLAY INVISIBLE (-5640 3510);
FORCEPROP 1 LASTPIN (-5650 3500) BN 1
J 2
(-5638 3508);
DISPLAY 0.489362 (-5638 3508);
PAINT MONO (-5638 3508);
FORCEPROP 2 LAST CDS_LIB mstr_standard
J 0
(-5700 3500);
DISPLAY INVISIBLE (-5700 3500);
FORCEPROP 1 LAST BODY_TYPE PLUMBING
J 2
(-5700 3550);
DISPLAY 0.872340 (-5700 3550);
PAINT GREEN (-5700 3550);
DISPLAY INVISIBLE (-5700 3550);
FORCEPROP 1 LAST HDL_TAP TRUE
J 2
(-6025 3375);
DISPLAY 0.872340 (-6025 3375);
DISPLAY INVISIBLE (-6025 3375);
FORCEPROP 1 LAST PATH I817
J 2
(-5698 3500);
DISPLAY 0.872340 (-5698 3500);
PAINT GREEN (-5698 3500);
DISPLAY INVISIBLE (-5698 3500);
FORCEADD TAP..1
R 2
(-5700 3550);
FORCEPROP 3 LASTPIN (-5650 3550) SIG_NAME M_A_CPU0_SB_CA<0>
J 0
(-5640 3560);
DISPLAY 0.659574 (-5640 3560);
PAINT MONO (-5640 3560);
DISPLAY INVISIBLE (-5640 3560);
FORCEPROP 1 LASTPIN (-5650 3550) BN 0
J 2
(-5638 3558);
DISPLAY 0.489362 (-5638 3558);
PAINT MONO (-5638 3558);
FORCEPROP 2 LAST CDS_LIB mstr_standard
J 0
(-5700 3550);
DISPLAY INVISIBLE (-5700 3550);
FORCEPROP 1 LAST BODY_TYPE PLUMBING
J 2
(-5700 3600);
DISPLAY 0.872340 (-5700 3600);
PAINT GREEN (-5700 3600);
DISPLAY INVISIBLE (-5700 3600);
FORCEPROP 1 LAST HDL_TAP TRUE
J 2
(-6025 3425);
DISPLAY 0.872340 (-6025 3425);
DISPLAY INVISIBLE (-6025 3425);
FORCEPROP 1 LAST PATH I818
J 2
(-5698 3550);
DISPLAY 0.872340 (-5698 3550);
PAINT GREEN (-5698 3550);
DISPLAY INVISIBLE (-5698 3550);
FORCEADD TAP..1
R 2
(-5700 3350);
FORCEPROP 3 LASTPIN (-5650 3350) SIG_NAME M_A_CPU0_SB_CA<4>
J 0
(-5640 3360);
DISPLAY 0.659574 (-5640 3360);
PAINT MONO (-5640 3360);
DISPLAY INVISIBLE (-5640 3360);
FORCEPROP 1 LASTPIN (-5650 3350) BN 4
J 2
(-5638 3358);
DISPLAY 0.489362 (-5638 3358);
PAINT MONO (-5638 3358);
FORCEPROP 2 LAST CDS_LIB mstr_standard
J 0
(-5700 3350);
DISPLAY INVISIBLE (-5700 3350);
FORCEPROP 1 LAST BODY_TYPE PLUMBING
J 2
(-5700 3400);
DISPLAY 0.872340 (-5700 3400);
PAINT GREEN (-5700 3400);
DISPLAY INVISIBLE (-5700 3400);
FORCEPROP 1 LAST HDL_TAP TRUE
J 2
(-6025 3225);
DISPLAY 0.872340 (-6025 3225);
DISPLAY INVISIBLE (-6025 3225);
FORCEPROP 1 LAST PATH I819
J 2
(-5698 3350);
DISPLAY 0.872340 (-5698 3350);
PAINT GREEN (-5698 3350);
DISPLAY INVISIBLE (-5698 3350);
FORCEADD TAP..1
R 2
(-5700 3400);
FORCEPROP 3 LASTPIN (-5650 3400) SIG_NAME M_A_CPU0_SB_CA<3>
J 0
(-5640 3410);
DISPLAY 0.659574 (-5640 3410);
PAINT MONO (-5640 3410);
DISPLAY INVISIBLE (-5640 3410);
FORCEPROP 1 LASTPIN (-5650 3400) BN 3
J 2
(-5638 3408);
DISPLAY 0.489362 (-5638 3408);
PAINT MONO (-5638 3408);
FORCEPROP 2 LAST CDS_LIB mstr_standard
J 0
(-5700 3400);
DISPLAY INVISIBLE (-5700 3400);
FORCEPROP 1 LAST BODY_TYPE PLUMBING
J 2
(-5700 3450);
DISPLAY 0.872340 (-5700 3450);
PAINT GREEN (-5700 3450);
DISPLAY INVISIBLE (-5700 3450);
FORCEPROP 1 LAST HDL_TAP TRUE
J 2
(-6025 3275);
DISPLAY 0.872340 (-6025 3275);
DISPLAY INVISIBLE (-6025 3275);
FORCEPROP 1 LAST PATH I820
J 2
(-5698 3400);
DISPLAY 0.872340 (-5698 3400);
PAINT GREEN (-5698 3400);
DISPLAY INVISIBLE (-5698 3400);
FORCEADD TAP..1
R 2
(-5700 3450);
FORCEPROP 3 LASTPIN (-5650 3450) SIG_NAME M_A_CPU0_SB_CA<2>
J 0
(-5640 3460);
DISPLAY 0.659574 (-5640 3460);
PAINT MONO (-5640 3460);
DISPLAY INVISIBLE (-5640 3460);
FORCEPROP 1 LASTPIN (-5650 3450) BN 2
J 2
(-5638 3458);
DISPLAY 0.489362 (-5638 3458);
PAINT MONO (-5638 3458);
FORCEPROP 2 LAST CDS_LIB mstr_standard
J 0
(-5700 3450);
DISPLAY INVISIBLE (-5700 3450);
FORCEPROP 1 LAST BODY_TYPE PLUMBING
J 2
(-5700 3500);
DISPLAY 0.872340 (-5700 3500);
PAINT GREEN (-5700 3500);
DISPLAY INVISIBLE (-5700 3500);
FORCEPROP 1 LAST HDL_TAP TRUE
J 2
(-6025 3325);
DISPLAY 0.872340 (-6025 3325);
DISPLAY INVISIBLE (-6025 3325);
FORCEPROP 1 LAST PATH I821
J 2
(-5698 3450);
DISPLAY 0.872340 (-5698 3450);
PAINT GREEN (-5698 3450);
DISPLAY INVISIBLE (-5698 3450);
FORCEADD TAP..1
R 2
(-5700 3250);
FORCEPROP 3 LASTPIN (-5650 3250) SIG_NAME M_A_CPU0_SB_CA<6>
J 0
(-5640 3260);
DISPLAY 0.659574 (-5640 3260);
PAINT MONO (-5640 3260);
DISPLAY INVISIBLE (-5640 3260);
FORCEPROP 1 LASTPIN (-5650 3250) BN 6
J 2
(-5638 3258);
DISPLAY 0.489362 (-5638 3258);
PAINT MONO (-5638 3258);
FORCEPROP 2 LAST CDS_LIB mstr_standard
J 0
(-5700 3250);
DISPLAY INVISIBLE (-5700 3250);
FORCEPROP 1 LAST BODY_TYPE PLUMBING
J 2
(-5700 3300);
DISPLAY 0.872340 (-5700 3300);
PAINT GREEN (-5700 3300);
DISPLAY INVISIBLE (-5700 3300);
FORCEPROP 1 LAST HDL_TAP TRUE
J 2
(-6025 3125);
DISPLAY 0.872340 (-6025 3125);
DISPLAY INVISIBLE (-6025 3125);
FORCEPROP 1 LAST PATH I822
J 2
(-5698 3250);
DISPLAY 0.872340 (-5698 3250);
PAINT GREEN (-5698 3250);
DISPLAY INVISIBLE (-5698 3250);
FORCEADD TAP..1
R 2
(-5700 3300);
FORCEPROP 3 LASTPIN (-5650 3300) SIG_NAME M_A_CPU0_SB_CA<5>
J 0
(-5640 3310);
DISPLAY 0.659574 (-5640 3310);
PAINT MONO (-5640 3310);
DISPLAY INVISIBLE (-5640 3310);
FORCEPROP 1 LASTPIN (-5650 3300) BN 5
J 2
(-5638 3308);
DISPLAY 0.489362 (-5638 3308);
PAINT MONO (-5638 3308);
FORCEPROP 2 LAST CDS_LIB mstr_standard
J 0
(-5700 3300);
DISPLAY INVISIBLE (-5700 3300);
FORCEPROP 1 LAST BODY_TYPE PLUMBING
J 2
(-5700 3350);
DISPLAY 0.872340 (-5700 3350);
PAINT GREEN (-5700 3350);
DISPLAY INVISIBLE (-5700 3350);
FORCEPROP 1 LAST HDL_TAP TRUE
J 2
(-6025 3175);
DISPLAY 0.872340 (-6025 3175);
DISPLAY INVISIBLE (-6025 3175);
FORCEPROP 1 LAST PATH I823
J 2
(-5698 3300);
DISPLAY 0.872340 (-5698 3300);
PAINT GREEN (-5698 3300);
DISPLAY INVISIBLE (-5698 3300);
FORCEADD OFFPAGE..2
R 2
(-6300 3975);
FORCEPROP 2 LAST $XR0 85 
J 0
(-6524 3975);
DISPLAY 0.638298 (-6524 3975);
PAINT MONO (-6524 3975);
FORCEPROP 2 LAST PATH I824
J 0
(-6550 4025);
DISPLAY 1.021277 (-6550 4025);
DISPLAY INVISIBLE (-6550 4025);
FORCEPROP 1 LAST COMMENT_BODY TRUE
J 2
(-6255 3880);
DISPLAY 0.872340 (-6255 3880);
PAINT GREEN (-6255 3880);
DISPLAY INVISIBLE (-6255 3880);
FORCEPROP 1 LAST OFFPAGE TRUE
J 2
(-6625 3850);
DISPLAY 0.872340 (-6625 3850);
PAINT GREEN (-6625 3850);
DISPLAY INVISIBLE (-6625 3850);
FORCEPROP 2 LAST CDS_LIB standard
J 0
(-6300 3975);
DISPLAY INVISIBLE (-6300 3975);
FORCEADD OFFPAGE..2
R 2
(-6300 3575);
FORCEPROP 2 LASTPIN (-6250 3575) SIG_NAME M_A_CPU0_SB_CA<6:0>
J 0
(-6285 3585);
DISPLAY 0.489362 (-6285 3585);
FORCEPROP 2 LAST $XR0 85 
J 0
(-6524 3575);
DISPLAY 0.638298 (-6524 3575);
PAINT MONO (-6524 3575);
FORCEPROP 2 LAST PATH I825
J 0
(-6550 3625);
DISPLAY 1.021277 (-6550 3625);
DISPLAY INVISIBLE (-6550 3625);
FORCEPROP 1 LAST COMMENT_BODY TRUE
J 2
(-6255 3480);
DISPLAY 0.872340 (-6255 3480);
PAINT GREEN (-6255 3480);
DISPLAY INVISIBLE (-6255 3480);
FORCEPROP 1 LAST OFFPAGE TRUE
J 2
(-6625 3450);
DISPLAY 0.872340 (-6625 3450);
PAINT GREEN (-6625 3450);
DISPLAY INVISIBLE (-6625 3450);
FORCEPROP 2 LAST CDS_LIB standard
J 0
(-6300 3575);
DISPLAY INVISIBLE (-6300 3575);
FORCEADD OFFPAGE..2
R 2
(-6300 3100);
FORCEPROP 2 LAST $XR0 85 
J 0
(-6524 3100);
DISPLAY 0.638298 (-6524 3100);
PAINT MONO (-6524 3100);
FORCEPROP 2 LAST PATH I826
J 0
(-6550 3150);
DISPLAY 1.021277 (-6550 3150);
DISPLAY INVISIBLE (-6550 3150);
FORCEPROP 1 LAST COMMENT_BODY TRUE
J 2
(-6255 3005);
DISPLAY 0.872340 (-6255 3005);
PAINT GREEN (-6255 3005);
DISPLAY INVISIBLE (-6255 3005);
FORCEPROP 1 LAST OFFPAGE TRUE
J 2
(-6625 2975);
DISPLAY 0.872340 (-6625 2975);
PAINT GREEN (-6625 2975);
DISPLAY INVISIBLE (-6625 2975);
FORCEPROP 2 LAST CDS_LIB standard
J 0
(-6300 3100);
DISPLAY INVISIBLE (-6300 3100);
FORCEADD OFFPAGE..2
R 2
(-6300 3050);
FORCEPROP 2 LAST $XR0 85 
J 0
(-6524 3050);
DISPLAY 0.638298 (-6524 3050);
PAINT MONO (-6524 3050);
FORCEPROP 2 LAST PATH I827
J 0
(-6550 3100);
DISPLAY 1.021277 (-6550 3100);
DISPLAY INVISIBLE (-6550 3100);
FORCEPROP 1 LAST COMMENT_BODY TRUE
J 2
(-6255 2955);
DISPLAY 0.872340 (-6255 2955);
PAINT GREEN (-6255 2955);
DISPLAY INVISIBLE (-6255 2955);
FORCEPROP 1 LAST OFFPAGE TRUE
J 2
(-6625 2925);
DISPLAY 0.872340 (-6625 2925);
PAINT GREEN (-6625 2925);
DISPLAY INVISIBLE (-6625 2925);
FORCEPROP 2 LAST CDS_LIB standard
J 0
(-6300 3050);
DISPLAY INVISIBLE (-6300 3050);
FORCEADD OFFPAGE..2
R 2
(-6300 2950);
FORCEPROP 2 LAST $XR0 85 
J 0
(-6524 2950);
DISPLAY 0.638298 (-6524 2950);
PAINT MONO (-6524 2950);
FORCEPROP 2 LAST PATH I828
J 0
(-6550 3000);
DISPLAY 1.021277 (-6550 3000);
DISPLAY INVISIBLE (-6550 3000);
FORCEPROP 1 LAST COMMENT_BODY TRUE
J 2
(-6255 2855);
DISPLAY 0.872340 (-6255 2855);
PAINT GREEN (-6255 2855);
DISPLAY INVISIBLE (-6255 2855);
FORCEPROP 1 LAST OFFPAGE TRUE
J 2
(-6625 2825);
DISPLAY 0.872340 (-6625 2825);
PAINT GREEN (-6625 2825);
DISPLAY INVISIBLE (-6625 2825);
FORCEPROP 2 LAST CDS_LIB standard
J 0
(-6300 2950);
DISPLAY INVISIBLE (-6300 2950);
FORCEADD OFFPAGE..2
R 2
(-6300 2900);
FORCEPROP 2 LAST $XR0 85 
J 0
(-6524 2900);
DISPLAY 0.638298 (-6524 2900);
PAINT MONO (-6524 2900);
FORCEPROP 2 LAST PATH I829
J 0
(-6550 2950);
DISPLAY 1.021277 (-6550 2950);
DISPLAY INVISIBLE (-6550 2950);
FORCEPROP 1 LAST COMMENT_BODY TRUE
J 2
(-6255 2805);
DISPLAY 0.872340 (-6255 2805);
PAINT GREEN (-6255 2805);
DISPLAY INVISIBLE (-6255 2805);
FORCEPROP 1 LAST OFFPAGE TRUE
J 2
(-6625 2775);
DISPLAY 0.872340 (-6625 2775);
PAINT GREEN (-6625 2775);
DISPLAY INVISIBLE (-6625 2775);
FORCEPROP 2 LAST CDS_LIB standard
J 0
(-6300 2900);
DISPLAY INVISIBLE (-6300 2900);
FORCEADD OFFPAGE..1
(-6300 2800);
FORCEPROP 2 LAST $XR0 85 
J 0
(-6521 2800);
DISPLAY 0.638298 (-6521 2800);
PAINT MONO (-6521 2800);
FORCEPROP 2 LAST PATH I830
J 0
(-6550 2850);
DISPLAY 1.021277 (-6550 2850);
DISPLAY INVISIBLE (-6550 2850);
FORCEPROP 1 LAST COMMENT_BODY TRUE
J 0
(-6175 2700);
DISPLAY 0.872340 (-6175 2700);
PAINT GREEN (-6175 2700);
DISPLAY INVISIBLE (-6175 2700);
FORCEPROP 1 LAST OFFPAGE TRUE
J 0
(-5975 2675);
DISPLAY 0.872340 (-5975 2675);
PAINT GREEN (-5975 2675);
DISPLAY INVISIBLE (-5975 2675);
FORCEPROP 2 LAST CDS_LIB standard
J 0
(-6300 2800);
DISPLAY INVISIBLE (-6300 2800);
FORCEADD OFFPAGE..2
R 2
(-6300 2600);
FORCEPROP 2 LAST $XR0 85 
J 0
(-6524 2600);
DISPLAY 0.638298 (-6524 2600);
PAINT MONO (-6524 2600);
FORCEPROP 2 LAST PATH I831
J 0
(-6550 2650);
DISPLAY 1.021277 (-6550 2650);
DISPLAY INVISIBLE (-6550 2650);
FORCEPROP 1 LAST COMMENT_BODY TRUE
J 2
(-6255 2505);
DISPLAY 0.872340 (-6255 2505);
PAINT GREEN (-6255 2505);
DISPLAY INVISIBLE (-6255 2505);
FORCEPROP 1 LAST OFFPAGE TRUE
J 2
(-6625 2475);
DISPLAY 0.872340 (-6625 2475);
PAINT GREEN (-6625 2475);
DISPLAY INVISIBLE (-6625 2475);
FORCEPROP 2 LAST CDS_LIB standard
J 0
(-6300 2600);
DISPLAY INVISIBLE (-6300 2600);
FORCEADD OFFPAGE..5
(-6300 2700);
FORCEPROP 2 LAST $XR0 85 
J 0
(-6524 2700);
DISPLAY 0.638298 (-6524 2700);
PAINT MONO (-6524 2700);
FORCEPROP 2 LAST PATH I832
J 0
(-6550 2750);
DISPLAY 1.021277 (-6550 2750);
DISPLAY INVISIBLE (-6550 2750);
FORCEPROP 1 LAST COMMENT_BODY TRUE
J 0
(-6200 2625);
DISPLAY 0.872340 (-6200 2625);
PAINT GREEN (-6200 2625);
DISPLAY INVISIBLE (-6200 2625);
FORCEPROP 1 LAST OFFPAGE TRUE
J 0
(-5975 2575);
DISPLAY 0.872340 (-5975 2575);
PAINT GREEN (-5975 2575);
DISPLAY INVISIBLE (-5975 2575);
FORCEPROP 2 LAST CDS_LIB mstr_standard
J 0
(-6300 2700);
DISPLAY INVISIBLE (-6300 2700);
FORCEADD OFFPAGE..2
R 2
(-6300 2550);
FORCEPROP 2 LAST $XR0 85 
J 0
(-6524 2550);
DISPLAY 0.638298 (-6524 2550);
PAINT MONO (-6524 2550);
FORCEPROP 2 LAST PATH I833
J 0
(-6550 2600);
DISPLAY 1.021277 (-6550 2600);
DISPLAY INVISIBLE (-6550 2600);
FORCEPROP 1 LAST COMMENT_BODY TRUE
J 2
(-6255 2455);
DISPLAY 0.872340 (-6255 2455);
PAINT GREEN (-6255 2455);
DISPLAY INVISIBLE (-6255 2455);
FORCEPROP 1 LAST OFFPAGE TRUE
J 2
(-6625 2425);
DISPLAY 0.872340 (-6625 2425);
PAINT GREEN (-6625 2425);
DISPLAY INVISIBLE (-6625 2425);
FORCEPROP 2 LAST CDS_LIB standard
J 0
(-6300 2550);
DISPLAY INVISIBLE (-6300 2550);
FORCEADD OFFPAGE..1
(-6300 2450);
FORCEPROP 2 LAST $XR0 85 
J 0
(-6521 2450);
DISPLAY 0.638298 (-6521 2450);
PAINT MONO (-6521 2450);
FORCEPROP 2 LAST PATH I834
J 0
(-6550 2500);
DISPLAY 1.021277 (-6550 2500);
DISPLAY INVISIBLE (-6550 2500);
FORCEPROP 1 LAST COMMENT_BODY TRUE
J 0
(-6175 2350);
DISPLAY 0.872340 (-6175 2350);
PAINT GREEN (-6175 2350);
DISPLAY INVISIBLE (-6175 2350);
FORCEPROP 1 LAST OFFPAGE TRUE
J 0
(-5975 2325);
DISPLAY 0.872340 (-5975 2325);
PAINT GREEN (-5975 2325);
DISPLAY INVISIBLE (-5975 2325);
FORCEPROP 2 LAST CDS_LIB standard
J 0
(-6300 2450);
DISPLAY INVISIBLE (-6300 2450);
FORCEADD OFFPAGE..5
(-6300 2350);
FORCEPROP 2 LAST $XR0 85 
J 0
(-6524 2350);
DISPLAY 0.638298 (-6524 2350);
PAINT MONO (-6524 2350);
FORCEPROP 2 LAST PATH I835
J 0
(-6550 2400);
DISPLAY 1.021277 (-6550 2400);
DISPLAY INVISIBLE (-6550 2400);
FORCEPROP 1 LAST COMMENT_BODY TRUE
J 0
(-6200 2275);
DISPLAY 0.872340 (-6200 2275);
PAINT GREEN (-6200 2275);
DISPLAY INVISIBLE (-6200 2275);
FORCEPROP 1 LAST OFFPAGE TRUE
J 0
(-5975 2225);
DISPLAY 0.872340 (-5975 2225);
PAINT GREEN (-5975 2225);
DISPLAY INVISIBLE (-5975 2225);
FORCEPROP 2 LAST CDS_LIB standard
J 0
(-6300 2350);
DISPLAY INVISIBLE (-6300 2350);
FORCEADD OFFPAGE..5
(-6300 2150);
FORCEPROP 2 LAST $XR0 85 
J 0
(-6524 2150);
DISPLAY 0.638298 (-6524 2150);
PAINT MONO (-6524 2150);
FORCEPROP 2 LAST PATH I836
J 0
(-6550 2200);
DISPLAY 1.021277 (-6550 2200);
DISPLAY INVISIBLE (-6550 2200);
FORCEPROP 1 LAST COMMENT_BODY TRUE
J 0
(-6200 2075);
DISPLAY 0.872340 (-6200 2075);
PAINT GREEN (-6200 2075);
DISPLAY INVISIBLE (-6200 2075);
FORCEPROP 1 LAST OFFPAGE TRUE
J 0
(-5975 2025);
DISPLAY 0.872340 (-5975 2025);
PAINT GREEN (-5975 2025);
DISPLAY INVISIBLE (-5975 2025);
FORCEPROP 2 LAST CDS_LIB standard
J 0
(-6300 2150);
DISPLAY INVISIBLE (-6300 2150);
FORCEADD Q_RES..1
(-6600 2250);
FORCEPROP 1 LAST LOCATION R375
J 0
(-6925 2250);
DISPLAY 0.489362 (-6925 2250);
PAINT SKYBLUE (-6925 2250);
FORCEPROP 0 LAST $SEC 1
J 0
(-6775 2300);
DISPLAY 0.680851 (-6775 2300);
PAINT MONO (-6775 2300);
DISPLAY INVISIBLE (-6775 2300);
FORCEPROP 0 LAST CDS_SEC 1
J 0
(-6775 2300);
DISPLAY 1.021277 (-6775 2300);
DISPLAY INVISIBLE (-6775 2300);
FORCEPROP 1 LASTPIN (-6700 2250) $PN 1
J 0
(-6688 2262);
DISPLAY 0.489362 (-6688 2262);
PAINT MONO (-6688 2262);
FORCEPROP 1 LASTPIN (-6500 2250) $PN 2
J 0
(-6538 2262);
DISPLAY 0.489362 (-6538 2262);
PAINT MONO (-6538 2262);
FORCEPROP 1 LAST TOLERANCE 1%
J 0
(-6325 2250);
DISPLAY 0.489362 (-6325 2250);
PAINT SKYBLUE (-6325 2250);
FORCEPROP 1 LAST VALUE 15   
J 2
(-6275 2250);
DISPLAY 0.489362 (-6275 2250);
PAINT SKYBLUE (-6275 2250);
FORCEPROP 1 LAST PART_NUMBER CS01502FB11
J 0
(-6475 2225);
DISPLAY 0.489362 (-6475 2225);
PAINT SKYBLUE (-6475 2225);
FORCEPROP 1 LAST PACK_TYPE 0402LF
J 0
(-6925 2225);
DISPLAY 0.489362 (-6925 2225);
PAINT SKYBLUE (-6925 2225);
FORCEPROP 2 LAST CDS_LIB pure_quanta
J 0
(-6600 2250);
DISPLAY INVISIBLE (-6600 2250);
FORCEPROP 1 LAST PATH I837
J 0
(-6650 2400);
DISPLAY 0.978723 (-6650 2400);
PAINT WHITE (-6650 2400);
DISPLAY INVISIBLE (-6650 2400);
FORCEPROP 1 LAST WATTAGE 1/16W
J 2
(-6375 2375);
DISPLAY 0.638298 (-6375 2375);
PAINT SKYBLUE (-6375 2375);
DISPLAY INVISIBLE (-6375 2375);
FORCEPROP 1 LAST MATERIAL CHIP
J 0
(-6725 2375);
DISPLAY 0.638298 (-6725 2375);
PAINT SKYBLUE (-6725 2375);
DISPLAY INVISIBLE (-6725 2375);
FORCEADD OFFPAGE..1
(-7900 2250);
FORCEPROP 2 LAST $XR0 85 
J 0
(-8151 2250);
DISPLAY 0.638298 (-8151 2250);
PAINT MONO (-8151 2250);
FORCEPROP 2 LAST PATH I838
J 0
(-8175 2300);
DISPLAY 1.021277 (-8175 2300);
DISPLAY INVISIBLE (-8175 2300);
FORCEPROP 1 LAST COMMENT_BODY TRUE
J 0
(-7775 2150);
DISPLAY 0.872340 (-7775 2150);
PAINT GREEN (-7775 2150);
DISPLAY INVISIBLE (-7775 2150);
FORCEPROP 1 LAST OFFPAGE TRUE
J 0
(-7575 2125);
DISPLAY 0.872340 (-7575 2125);
PAINT GREEN (-7575 2125);
DISPLAY INVISIBLE (-7575 2125);
FORCEPROP 2 LAST CDS_LIB mstr_standard
J 0
(-7900 2250);
DISPLAY INVISIBLE (-7900 2250);
FORCEADD CAD_NOTE..1
(-7550 2500);
FORCEPROP 0 LAST L1 R1941 PLACE CLOSE TO DIMM < 25MM
J 0
(-7700 2375);
DISPLAY 0.617021 (-7700 2375);
PAINT WHITE (-7700 2375);
FORCEPROP 2 LAST CDS_LIB pure_quanta_power
J 0
(-7550 2500);
DISPLAY INVISIBLE (-7550 2500);
FORCEPROP 1 LAST COMMENT_BODY TRUE
J 0
(-7525 2600);
DISPLAY 0.574468 (-7525 2600);
PAINT WHITE (-7525 2600);
DISPLAY INVISIBLE (-7525 2600);
FORCEADD QUANTA_TITLE_BLOCK_C..1
(-100 100);
FORCEPROP 0 LAST CDS_CON_LAST_MODIFIED Fri Mar 11 14:52:10 2022
J 0
(-1985 115);
DISPLAY INVISIBLE (-1985 115);
FORCEPROP 1 LAST CUSTOM_TXT_CDS <CON_LAST_MODIFIED>
J 0
(-1985 115);
DISPLAY 0.978723 (-1985 115);
FORCEPROP 2 LAST CUSTOM_TXT_CDS <XR_PAGE_TITLE>
J 0
(-7990 5350);
DISPLAY 0.638298 (-7990 5350);
PAINT PINK (-7990 5350);
DISPLAY INVISIBLE (-7990 5350);
FORCEPROP 1 LAST CUSTOM_TXT_CDS <NAME_2>
J 0
(-3275 150);
FORCEPROP 1 LAST CUSTOM_TXT_CDS <NAME_1>
J 0
(-3275 275);
FORCEPROP 1 LAST CUSTOM_TXT_CDS <Q_NUMBER>
J 0
(-1503 203);
DISPLAY 1.212766 (-1503 203);
FORCEPROP 1 LAST CUSTOM_TXT_CDS <Q_PROJ>
J 0
(-2482 202);
DISPLAY 1.212766 (-2482 202);
FORCEPROP 1 LAST CUSTOM_TXT_CDS <Q_REV>
J 0
(-284 203);
DISPLAY 1.212766 (-284 203);
FORCEPROP 1 LAST CUSTOM_TXT_CDS <CON_PAGE_NUM> OF <CON_TOTAL_PAGES>
J 0
(-546 118);
DISPLAY 0.978723 (-546 118);
FORCEPROP 1 LAST Q_TITLE CPU0 DDR CHA
J 0
(-9425 150);
DISPLAY 2.446809 (-9425 150);
PAINT GREEN (-9425 150);
FORCEPROP 1 LAST Q_DEPT BU9
J 1
(-3863 149);
DISPLAY 1.957447 (-3863 149);
PAINT GREEN (-3863 149);
FORCEPROP 2 LAST PAGE_BORDER TRUE
J 0
(-7990 5350);
DISPLAY 0.638298 (-7990 5350);
PAINT PINK (-7990 5350);
DISPLAY INVISIBLE (-7990 5350);
FORCEPROP 1 LAST CDS_LMAN_SYM_OUTLINE -9475,6775,100,-125
J 0
(-100 100);
DISPLAY 0.468085 (-100 100);
PAINT GREEN (-100 100);
DISPLAY INVISIBLE (-100 100);
FORCEPROP 2 LAST CDS_LIB pure_quanta
J 0
(-100 100);
DISPLAY INVISIBLE (-100 100);
FORCEPROP 1 LAST COMMENT_BODY TRUE
J 0
(-88 87);
DISPLAY 0.978723 (-88 87);
PAINT GREEN (-88 87);
DISPLAY INVISIBLE (-88 87);
FORCEPROP 2 LAST CDS_XR_PAGE_TITLE CR-10 : @T6G_MB_LIB.T6G(SCH_1):PAGE10
J 0
(-7990 5350);
DISPLAY 0.638298 (-7990 5350);
PAINT PINK (-7990 5350);
DISPLAY INVISIBLE (-7990 5350);
WIRE 17 -1 (-2975 5925)(-2975 5875);
WIRE 17 -1 (-2975 5975)(-2975 5925);
WIRE 17 -1 (-2975 5875)(-2975 5825);
WIRE 17 -1 (-2975 5825)(-2975 5775);
WIRE 17 -1 (-2975 6025)(-2975 5975);
WIRE 17 -1 (-2975 6075)(-2975 6025);
WIRE 17 -1 (-2975 5775)(-2975 5675);
WIRE 17 -1 (-2975 5675)(-2975 5625);
WIRE 17 -1 (-2975 6125)(-2975 6075);
WIRE 17 -1 (-2975 6125)(-2350 6125);
FORCEPROP 2 LAST SIG_NAME M_A_CPU0_SA_DQ<31:0>
J 0
(-2960 6135);
DISPLAY 0.489362 (-2960 6135);
WIRE 17 -1 (-2975 5625)(-2975 5575);
WIRE 17 -1 (-2975 5575)(-2975 5525);
WIRE 17 -1 (-2975 5525)(-2975 5475);
WIRE 17 -1 (-2975 5475)(-2975 5425);
WIRE 17 -1 (-2975 5425)(-2975 5375);
WIRE 17 -1 (-2975 5375)(-2975 5325);
WIRE 17 -1 (-2975 5225)(-2975 5325);
WIRE 17 -1 (-2975 5175)(-2975 5225);
WIRE 17 -1 (-2975 5125)(-2975 5175);
WIRE 17 -1 (-2975 5075)(-2975 5125);
WIRE 17 -1 (-2975 5075)(-2975 5025);
WIRE 17 -1 (-2975 5025)(-2975 4975);
WIRE 17 -1 (-2975 4975)(-2975 4925);
WIRE 17 -1 (-2975 4925)(-2975 4875);
WIRE 17 -1 (-2975 4875)(-2975 4775);
WIRE 17 -1 (-2975 4775)(-2975 4725);
WIRE 17 -1 (-2975 4725)(-2975 4675);
WIRE 17 -1 (-2975 4675)(-2975 4625);
WIRE 17 -1 (-2975 4575)(-2975 4625);
WIRE 17 -1 (-2975 4525)(-2975 4575);
WIRE 17 -1 (-2975 4475)(-2975 4525);
WIRE 17 -1 (-2975 4425)(-2975 4475);
WIRE 17 -1 (-2975 4175)(-2975 4125);
WIRE 17 -1 (-2975 4225)(-2975 4175);
WIRE 17 -1 (-2975 4125)(-2975 4075);
WIRE 17 -1 (-2975 4075)(-2975 4025);
WIRE 17 -1 (-2975 4275)(-2975 4225);
WIRE 17 -1 (-2975 4325)(-2975 4275);
WIRE 17 -1 (-2975 4025)(-2975 3975);
WIRE 17 -1 (-2975 3975)(-2975 3875);
WIRE 17 -1 (-2975 4325)(-2350 4325);
FORCEPROP 2 LAST SIG_NAME M_A_CPU0_SB_DQ<31:0>
J 0
(-2935 4335);
DISPLAY 0.489362 (-2935 4335);
WIRE 17 -1 (-2975 3875)(-2975 3825);
WIRE 17 -1 (-2975 3825)(-2975 3775);
WIRE 17 -1 (-2975 3775)(-2975 3725);
WIRE 17 -1 (-2975 3725)(-2975 3675);
WIRE 17 -1 (-2975 3675)(-2975 3625);
WIRE 17 -1 (-2975 3625)(-2975 3575);
WIRE 17 -1 (-2975 3575)(-2975 3525);
WIRE 17 -1 (-2975 3425)(-2975 3525);
WIRE 17 -1 (-2975 3375)(-2975 3425);
WIRE 17 -1 (-2975 3325)(-2975 3375);
WIRE 17 -1 (-2975 3275)(-2975 3325);
WIRE 17 -1 (-2975 3275)(-2975 3225);
WIRE 17 -1 (-2975 3225)(-2975 3175);
WIRE 17 -1 (-2975 3175)(-2975 3125);
WIRE 17 -1 (-2975 3125)(-2975 3075);
WIRE 17 -1 (-2975 3075)(-2975 2975);
WIRE 17 -1 (-2975 2975)(-2975 2925);
WIRE 17 -1 (-2975 2925)(-2975 2875);
WIRE 17 -1 (-2975 2875)(-2975 2825);
WIRE 17 -1 (-2975 2775)(-2975 2825);
WIRE 17 -1 (-2975 2725)(-2975 2775);
WIRE 17 -1 (-2975 2675)(-2975 2725);
WIRE 17 -1 (-2975 2625)(-2975 2675);
WIRE 17 -1 (-2975 2525)(-2975 2550);
FORCEPROP 2 LAST SIG_NAME M_A_CPU0_SA_CB<7:0>
J 0
(-2985 2560);
DISPLAY 0.489362 (-2985 2560);
WIRE 17 -1 (-2975 2425)(-2975 2475);
WIRE 17 -1 (-2975 2425)(-2975 2375);
WIRE 17 -1 (-2975 2525)(-2975 2475);
WIRE 17 -1 (-2975 2325)(-2975 2375);
WIRE 17 -1 (-2975 2275)(-2975 2325);
WIRE 17 -1 (-2975 2225)(-2975 2275);
WIRE 17 -1 (-2975 2175)(-2975 2225);
WIRE 17 -1 (-2975 2075)(-2975 2025);
WIRE 17 -1 (-2975 2075)(-2975 2100);
WIRE 17 -1 (-2975 1975)(-2975 2025);
WIRE 17 -1 (-2975 1975)(-2975 1925);
WIRE 17 -1 (-2975 2100)(-2475 2100);
FORCEPROP 2 LAST SIG_NAME M_A_CPU0_SB_CB<7:0>
J 0
(-2960 2110);
DISPLAY 0.489362 (-2960 2110);
WIRE 17 -1 (-2975 1875)(-2975 1925);
WIRE 17 -1 (-2975 1825)(-2975 1875);
WIRE 17 -1 (-2975 1775)(-2975 1825);
WIRE 17 -1 (-2975 1725)(-2975 1775);
WIRE 17 -1 (-5600 6125)(-5600 6025);
WIRE 17 -1 (-5600 6125)(-6400 6125);
FORCEPROP 2 LAST SIG_NAME M_A_CPU0_SA_DQS_DP<9:0>
J 0
(-6410 6135);
DISPLAY 0.489362 (-6410 6135);
WIRE 17 -1 (-5600 6025)(-5600 5925);
WIRE 17 -1 (-5600 5925)(-5600 5825);
WIRE 17 -1 (-5600 5825)(-5600 5725);
WIRE 17 -1 (-5600 5625)(-5600 5725);
WIRE 17 -1 (-5600 5525)(-5600 5625);
WIRE 17 -1 (-5600 5425)(-5600 5525);
WIRE 17 -1 (-5600 5425)(-5600 5325);
WIRE 17 -1 (-5600 5325)(-5600 5225);
WIRE 17 -1 (-5800 6075)(-5800 5975);
WIRE 17 -1 (-5800 6075)(-6400 6075);
FORCEPROP 2 LAST SIG_NAME M_A_CPU0_SA_DQS_DN<9:0>
J 0
(-6410 6085);
DISPLAY 0.489362 (-6410 6085);
WIRE 17 -1 (-5800 5375)(-5800 5275);
WIRE 17 -1 (-5800 5375)(-5800 5475);
WIRE 17 -1 (-5800 5275)(-5800 5175);
WIRE 17 -1 (-5800 5475)(-5800 5575);
WIRE 17 -1 (-5800 5575)(-5800 5675);
WIRE 17 -1 (-5800 5775)(-5800 5675);
WIRE 17 -1 (-5800 5875)(-5800 5775);
WIRE 17 -1 (-5800 5975)(-5800 5875);
WIRE 17 -1 (-5600 4975)(-5600 4875);
WIRE 17 -1 (-5600 5075)(-5600 4975);
WIRE 17 -1 (-5600 4875)(-5600 4775);
WIRE 17 -1 (-5600 4775)(-5600 4675);
WIRE 17 -1 (-5600 5075)(-6400 5075);
FORCEPROP 2 LAST SIG_NAME M_A_CPU0_SB_DQS_DP<9:0>
J 0
(-6435 5085);
DISPLAY 0.489362 (-6435 5085);
WIRE 17 -1 (-5600 4575)(-5600 4675);
WIRE 17 -1 (-5600 4475)(-5600 4575);
WIRE 17 -1 (-5600 4375)(-5600 4475);
WIRE 17 -1 (-5600 4375)(-5600 4275);
WIRE 17 -1 (-5600 4275)(-5600 4175);
WIRE 17 -1 (-5800 4525)(-5800 4625);
WIRE 17 -1 (-5800 4425)(-5800 4525);
WIRE 17 -1 (-5800 4725)(-5800 4625);
WIRE 17 -1 (-5800 4825)(-5800 4725);
WIRE 17 -1 (-5800 4325)(-5800 4425);
WIRE 17 -1 (-5800 4325)(-5800 4225);
WIRE 17 -1 (-5800 4925)(-5800 4825);
WIRE 17 -1 (-5800 5025)(-5800 4925);
WIRE 17 -1 (-5800 4225)(-5800 4125);
WIRE 17 -1 (-5800 5025)(-6400 5025);
WIRE 17 -1 (-5750 3925)(-5750 3975);
WIRE 17 -1 (-5750 3875)(-5750 3925);
WIRE 17 -1 (-5750 3975)(-6250 3975);
FORCEPROP 2 LAST SIG_NAME M_A_CPU0_SA_CA<6:0>
J 0
(-6285 3985);
DISPLAY 0.489362 (-6285 3985);
WIRE 17 -1 (-5750 3525)(-5750 3575);
WIRE 17 -1 (-5750 3475)(-5750 3525);
WIRE 17 -1 (-5750 3575)(-6250 3575);
WIRE 17 -1 (-5750 3825)(-5750 3875);
WIRE 17 -1 (-5750 3425)(-5750 3475);
WIRE 17 -1 (-5750 3375)(-5750 3425);
WIRE 17 -1 (-5750 3325)(-5750 3375);
WIRE 17 -1 (-5750 3775)(-5750 3825);
WIRE 17 -1 (-5750 3725)(-5750 3775);
WIRE 17 -1 (-5750 3675)(-5750 3725);
WIRE 17 -1 (-5750 3275)(-5750 3325);
WIRE 17 -1 (-2975 2550)(-2475 2550);
WIRE 16 -1 (-7850 2250)(-6700 2250);
FORCEPROP 2 LAST SIG_NAME M_A_CPU0_ALERT_N
J 0
(-7710 2260);
DISPLAY 0.489362 (-7710 2260);
WIRE 16 -1 (-6250 1300)(-5150 1300);
FORCEPROP 2 LAST SIG_NAME TP_M_A_CPU0_SA_TEST39A
J 0
(-6235 1310);
DISPLAY 0.489362 (-6235 1310);
FORCEPROP 2 LASTPROP $XRERR UNIQUE?
J 0
(-6490 1300);
DISPLAY 0.638298 (-6490 1300);
PAINT MONO (-6490 1300);
DISPLAY INVISIBLE (-6490 1300);
WIRE 16 -1 (-6250 1250)(-5150 1250);
FORCEPROP 2 LAST SIG_NAME TP_M_A_CPU0_SA_TEST40
J 0
(-6235 1260);
DISPLAY 0.489362 (-6235 1260);
FORCEPROP 2 LASTPROP $XRERR UNIQUE?
J 0
(-6490 1250);
DISPLAY 0.638298 (-6490 1250);
PAINT MONO (-6490 1250);
DISPLAY INVISIBLE (-6490 1250);
WIRE 16 -1 (-6500 2250)(-5150 2250);
FORCEPROP 2 LAST SIG_NAME M_A_CPU0_ALERT_R_N
J 0
(-6235 2260);
DISPLAY 0.489362 (-6235 2260);
FORCEPROP 2 LASTPROP $XRERR UNIQUE?
J 0
(-6475 2260);
DISPLAY 0.638298 (-6475 2260);
PAINT MONO (-6475 2260);
DISPLAY INVISIBLE (-6475 2260);
WIRE 16 -1 (-6250 3100)(-5150 3100);
FORCEPROP 2 LAST SIG_NAME M_A_CPU0_CLK_DP<0>
J 0
(-6250 3110);
DISPLAY 0.489362 (-6250 3110);
WIRE 16 -1 (-6250 3050)(-5150 3050);
FORCEPROP 2 LAST SIG_NAME M_A_CPU0_CLK_DN<0>
J 0
(-6250 3060);
DISPLAY 0.489362 (-6250 3060);
WIRE 16 -1 (-6250 2950)(-5150 2950);
FORCEPROP 2 LAST SIG_NAME M_A_CPU0_SA_CS_N<0>
J 0
(-6250 2960);
DISPLAY 0.489362 (-6250 2960);
WIRE 16 -1 (-6250 2900)(-5150 2900);
FORCEPROP 2 LAST SIG_NAME M_A_CPU0_SA_CS_N<1>
J 0
(-6250 2910);
DISPLAY 0.489362 (-6250 2910);
WIRE 16 -1 (-6250 2800)(-5150 2800);
FORCEPROP 2 LAST SIG_NAME M_A_CPU0_SA_RSP<0>
J 0
(-6250 2810);
DISPLAY 0.489362 (-6250 2810);
WIRE 16 -1 (-6250 2600)(-5150 2600);
FORCEPROP 2 LAST SIG_NAME M_A_CPU0_SB_CS_N<0>
J 0
(-6250 2610);
DISPLAY 0.489362 (-6250 2610);
WIRE 16 -1 (-6250 2700)(-5150 2700);
FORCEPROP 2 LAST SIG_NAME M_A_CPU0_SA_PAR
J 0
(-6250 2710);
DISPLAY 0.489362 (-6250 2710);
WIRE 16 -1 (-6250 2550)(-5150 2550);
FORCEPROP 2 LAST SIG_NAME M_A_CPU0_SB_CS_N<1>
J 0
(-6250 2560);
DISPLAY 0.489362 (-6250 2560);
WIRE 16 -1 (-6250 2450)(-5150 2450);
FORCEPROP 2 LAST SIG_NAME M_A_CPU0_SB_RSP<0>
J 0
(-6250 2460);
DISPLAY 0.489362 (-6250 2460);
WIRE 16 -1 (-6250 2350)(-5150 2350);
FORCEPROP 2 LAST SIG_NAME M_A_CPU0_SB_PAR
J 0
(-6250 2360);
DISPLAY 0.489362 (-6250 2360);
WIRE 16 -1 (-6250 2150)(-5150 2150);
FORCEPROP 2 LAST SIG_NAME M_A_CPU0_RESET_N
J 0
(-6250 2160);
DISPLAY 0.489362 (-6250 2160);
WIRE 16 -1 (-5650 3250)(-5150 3250);
WIRE 16 -1 (-5650 3650)(-5150 3650);
WIRE 16 -1 (-5650 3300)(-5150 3300);
WIRE 16 -1 (-5650 3700)(-5150 3700);
WIRE 16 -1 (-5650 3350)(-5150 3350);
WIRE 16 -1 (-5650 3750)(-5150 3750);
WIRE 16 -1 (-5650 3400)(-5150 3400);
WIRE 16 -1 (-5650 3800)(-5150 3800);
WIRE 16 -1 (-5650 3450)(-5150 3450);
WIRE 16 -1 (-5650 3850)(-5150 3850);
WIRE 16 -1 (-5650 3500)(-5150 3500);
WIRE 16 -1 (-5650 3900)(-5150 3900);
WIRE 16 -1 (-5650 3550)(-5150 3550);
WIRE 16 -1 (-5650 3950)(-5150 3950);
WIRE 16 -1 (-5700 4600)(-5150 4600);
WIRE 16 -1 (-5700 4700)(-5150 4700);
WIRE 16 -1 (-5700 4800)(-5150 4800);
WIRE 16 -1 (-5700 4900)(-5150 4900);
WIRE 16 -1 (-5700 5000)(-5150 5000);
WIRE 16 -1 (-5700 4100)(-5150 4100);
WIRE 16 -1 (-5700 4200)(-5150 4200);
WIRE 16 -1 (-5700 4300)(-5150 4300);
WIRE 16 -1 (-5700 4400)(-5150 4400);
WIRE 16 -1 (-5700 4500)(-5150 4500);
WIRE 16 -1 (-5500 4150)(-5150 4150);
WIRE 16 -1 (-5500 4250)(-5150 4250);
WIRE 16 -1 (-5500 4350)(-5150 4350);
WIRE 16 -1 (-5500 4450)(-5150 4450);
WIRE 16 -1 (-5500 4550)(-5150 4550);
WIRE 16 -1 (-5500 5050)(-5150 5050);
WIRE 16 -1 (-5500 4650)(-5150 4650);
WIRE 16 -1 (-5500 4750)(-5150 4750);
WIRE 16 -1 (-5500 4850)(-5150 4850);
WIRE 16 -1 (-5500 4950)(-5150 4950);
WIRE 16 -1 (-5700 5150)(-5150 5150);
WIRE 16 -1 (-5700 5250)(-5150 5250);
WIRE 16 -1 (-5700 5450)(-5150 5450);
WIRE 16 -1 (-5700 5550)(-5150 5550);
WIRE 16 -1 (-5700 5650)(-5150 5650);
WIRE 16 -1 (-5700 5750)(-5150 5750);
WIRE 16 -1 (-5700 5850)(-5150 5850);
WIRE 16 -1 (-5700 5350)(-5150 5350);
WIRE 16 -1 (-5700 5950)(-5150 5950);
WIRE 16 -1 (-5700 6050)(-5150 6050);
WIRE 16 -1 (-5500 5500)(-5150 5500);
WIRE 16 -1 (-5500 5600)(-5150 5600);
WIRE 16 -1 (-5500 5200)(-5150 5200);
WIRE 16 -1 (-5500 5300)(-5150 5300);
WIRE 16 -1 (-5500 5400)(-5150 5400);
WIRE 16 -1 (-5500 5700)(-5150 5700);
WIRE 16 -1 (-5500 5800)(-5150 5800);
WIRE 16 -1 (-5500 5900)(-5150 5900);
WIRE 16 -1 (-5500 6000)(-5150 6000);
WIRE 16 -1 (-5500 6100)(-5150 6100);
WIRE 16 -1 (-3075 1700)(-3550 1700);
WIRE 16 -1 (-3075 1750)(-3550 1750);
WIRE 16 -1 (-3075 1800)(-3550 1800);
WIRE 16 -1 (-3075 1850)(-3550 1850);
WIRE 16 -1 (-3075 1900)(-3550 1900);
WIRE 16 -1 (-3075 1950)(-3550 1950);
WIRE 16 -1 (-3075 2000)(-3550 2000);
WIRE 16 -1 (-3075 2150)(-3550 2150);
WIRE 16 -1 (-3075 2200)(-3550 2200);
WIRE 16 -1 (-3075 2050)(-3550 2050);
WIRE 16 -1 (-3075 2250)(-3550 2250);
WIRE 16 -1 (-3075 2300)(-3550 2300);
WIRE 16 -1 (-3075 2350)(-3550 2350);
WIRE 16 -1 (-3075 2400)(-3550 2400);
WIRE 16 -1 (-3075 2450)(-3550 2450);
WIRE 16 -1 (-3075 2500)(-3550 2500);
WIRE 16 -1 (-3075 2750)(-3550 2750);
WIRE 16 -1 (-3075 2800)(-3550 2800);
WIRE 16 -1 (-3075 2850)(-3550 2850);
WIRE 16 -1 (-3075 2900)(-3550 2900);
WIRE 16 -1 (-3075 2950)(-3550 2950);
WIRE 16 -1 (-3075 3050)(-3550 3050);
WIRE 16 -1 (-3075 2600)(-3550 2600);
WIRE 16 -1 (-3075 2650)(-3550 2650);
WIRE 16 -1 (-3075 2700)(-3550 2700);
WIRE 16 -1 (-3075 3350)(-3550 3350);
WIRE 16 -1 (-3075 3400)(-3550 3400);
WIRE 16 -1 (-3075 3500)(-3550 3500);
WIRE 16 -1 (-3075 3550)(-3550 3550);
WIRE 16 -1 (-3075 3100)(-3550 3100);
WIRE 16 -1 (-3075 3150)(-3550 3150);
WIRE 16 -1 (-3075 3200)(-3550 3200);
WIRE 16 -1 (-3075 3250)(-3550 3250);
WIRE 16 -1 (-3075 3300)(-3550 3300);
WIRE 16 -1 (-3075 3600)(-3550 3600);
WIRE 16 -1 (-3075 3650)(-3550 3650);
WIRE 16 -1 (-3075 3700)(-3550 3700);
WIRE 16 -1 (-3075 3750)(-3550 3750);
WIRE 16 -1 (-3075 3800)(-3550 3800);
WIRE 16 -1 (-3075 3850)(-3550 3850);
WIRE 16 -1 (-3075 3950)(-3550 3950);
WIRE 16 -1 (-3075 4000)(-3550 4000);
WIRE 16 -1 (-3550 4050)(-3075 4050);
WIRE 16 -1 (-3075 4200)(-3550 4200);
WIRE 16 -1 (-3075 4250)(-3550 4250);
WIRE 16 -1 (-3550 4300)(-3075 4300);
WIRE 16 -1 (-3550 4500)(-3075 4500);
WIRE 16 -1 (-3550 4550)(-3075 4550);
WIRE 16 -1 (-3550 4600)(-3075 4600);
WIRE 16 -1 (-3550 4400)(-3075 4400);
WIRE 16 -1 (-3550 4450)(-3075 4450);
WIRE 16 -1 (-3075 4100)(-3550 4100);
WIRE 16 -1 (-3075 4150)(-3550 4150);
WIRE 16 -1 (-3550 5050)(-3075 5050);
WIRE 16 -1 (-3550 5100)(-3075 5100);
WIRE 16 -1 (-3550 4650)(-3075 4650);
WIRE 16 -1 (-3550 4700)(-3075 4700);
WIRE 16 -1 (-3550 4750)(-3075 4750);
WIRE 16 -1 (-3550 4850)(-3075 4850);
WIRE 16 -1 (-3550 4900)(-3075 4900);
WIRE 16 -1 (-3550 4950)(-3075 4950);
WIRE 16 -1 (-3550 5000)(-3075 5000);
WIRE 16 -1 (-3550 5150)(-3075 5150);
WIRE 16 -1 (-3550 5200)(-3075 5200);
WIRE 16 -1 (-3550 5300)(-3075 5300);
WIRE 16 -1 (-3550 5350)(-3075 5350);
WIRE 16 -1 (-3550 5400)(-3075 5400);
WIRE 16 -1 (-3550 5600)(-3075 5600);
WIRE 16 -1 (-3550 5450)(-3075 5450);
WIRE 16 -1 (-3550 5500)(-3075 5500);
WIRE 16 -1 (-3550 5550)(-3075 5550);
WIRE 16 -1 (-3550 5950)(-3075 5950);
WIRE 16 -1 (-3550 6000)(-3075 6000);
WIRE 16 -1 (-3550 6050)(-3075 6050);
WIRE 16 -1 (-3550 6100)(-3075 6100);
WIRE 16 -1 (-3550 5650)(-3075 5650);
WIRE 16 -1 (-3550 5750)(-3075 5750);
WIRE 16 -1 (-3550 5800)(-3075 5800);
WIRE 16 -1 (-3550 5850)(-3075 5850);
WIRE 16 -1 (-3550 5900)(-3075 5900);
QUIT
